(kicad_sch
	(version 20250114)
	(generator "eeschema")
	(generator_version "9.0")
	(paper "A3")
	(title_block
		(title "Kintex 410T devboard")
		(date "2024-04-03")
		(rev "1.1.2")
	)
	(text "Trace length from the resistor pins to the\nFPGA pins MGTRREF and MGTAVTTRCAL\nmust be equal in length."
		(exclude_from_sim no)
		(at 245.11 82.55 0)
		(effects
			(font
				(size 1.27 1.27)
			)
			(justify left bottom)
		)
	)
	(text "USER IO Voltage selection"
		(exclude_from_sim no)
		(at 351.155 213.995 0)
		(effects
			(font
				(size 1.27 1.27)
				(thickness 0.4)
				(bold yes)
			)
			(justify left bottom)
		)
	)
	(junction
		(at 195.58 96.52)
		(diameter 0)
		(color 0 0 0 0)
	)
	(junction
		(at 191.77 153.67)
		(diameter 0)
		(color 0 0 0 0)
	)
	(junction
		(at 157.48 78.74)
		(diameter 0)
		(color 0 0 0 0)
	)
	(junction
		(at 229.87 194.31)
		(diameter 0)
		(color 0 0 0 0)
	)
	(junction
		(at 180.34 68.58)
		(diameter 0)
		(color 0 0 0 0)
	)
	(junction
		(at 191.77 143.51)
		(diameter 0)
		(color 0 0 0 0)
	)
	(junction
		(at 165.1 29.21)
		(diameter 0)
		(color 0 0 0 0)
	)
	(junction
		(at 161.29 194.31)
		(diameter 0)
		(color 0 0 0 0)
	)
	(junction
		(at 172.72 78.74)
		(diameter 0)
		(color 0 0 0 0)
	)
	(junction
		(at 222.25 171.45)
		(diameter 0)
		(color 0 0 0 0)
	)
	(junction
		(at 210.82 96.52)
		(diameter 0)
		(color 0 0 0 0)
	)
	(junction
		(at 172.72 68.58)
		(diameter 0)
		(color 0 0 0 0)
	)
	(junction
		(at 153.67 231.14)
		(diameter 0)
		(color 0 0 0 0)
	)
	(junction
		(at 203.2 39.37)
		(diameter 0)
		(color 0 0 0 0)
	)
	(junction
		(at 138.43 241.3)
		(diameter 0)
		(color 0 0 0 0)
	)
	(junction
		(at 381 250.19)
		(diameter 0)
		(color 0 0 0 0)
	)
	(junction
		(at 222.25 213.36)
		(diameter 0)
		(color 0 0 0 0)
	)
	(junction
		(at 237.49 194.31)
		(diameter 0)
		(color 0 0 0 0)
	)
	(junction
		(at 107.95 231.14)
		(diameter 0)
		(color 0 0 0 0)
	)
	(junction
		(at 165.1 39.37)
		(diameter 0)
		(color 0 0 0 0)
	)
	(junction
		(at 149.86 29.21)
		(diameter 0)
		(color 0 0 0 0)
	)
	(junction
		(at 149.86 39.37)
		(diameter 0)
		(color 0 0 0 0)
	)
	(junction
		(at 168.91 223.52)
		(diameter 0)
		(color 0 0 0 0)
	)
	(junction
		(at 149.86 78.74)
		(diameter 0)
		(color 0 0 0 0)
	)
	(junction
		(at 210.82 29.21)
		(diameter 0)
		(color 0 0 0 0)
	)
	(junction
		(at 218.44 39.37)
		(diameter 0)
		(color 0 0 0 0)
	)
	(junction
		(at 149.86 96.52)
		(diameter 0)
		(color 0 0 0 0)
	)
	(junction
		(at 157.48 29.21)
		(diameter 0)
		(color 0 0 0 0)
	)
	(junction
		(at 226.06 39.37)
		(diameter 0)
		(color 0 0 0 0)
	)
	(junction
		(at 107.95 241.3)
		(diameter 0)
		(color 0 0 0 0)
	)
	(junction
		(at 168.91 213.36)
		(diameter 0)
		(color 0 0 0 0)
	)
	(junction
		(at 187.96 96.52)
		(diameter 0)
		(color 0 0 0 0)
	)
	(junction
		(at 219.71 45.72)
		(diameter 0)
		(color 0 0 0 0)
	)
	(junction
		(at 229.87 241.3)
		(diameter 0)
		(color 0 0 0 0)
	)
	(junction
		(at 172.72 39.37)
		(diameter 0)
		(color 0 0 0 0)
	)
	(junction
		(at 233.68 45.72)
		(diameter 0)
		(color 0 0 0 0)
	)
	(junction
		(at 199.39 223.52)
		(diameter 0)
		(color 0 0 0 0)
	)
	(junction
		(at 146.05 223.52)
		(diameter 0)
		(color 0 0 0 0)
	)
	(junction
		(at 207.01 213.36)
		(diameter 0)
		(color 0 0 0 0)
	)
	(junction
		(at 199.39 153.67)
		(diameter 0)
		(color 0 0 0 0)
	)
	(junction
		(at 184.15 143.51)
		(diameter 0)
		(color 0 0 0 0)
	)
	(junction
		(at 157.48 68.58)
		(diameter 0)
		(color 0 0 0 0)
	)
	(junction
		(at 138.43 231.14)
		(diameter 0)
		(color 0 0 0 0)
	)
	(junction
		(at 180.34 86.36)
		(diameter 0)
		(color 0 0 0 0)
	)
	(junction
		(at 165.1 86.36)
		(diameter 0)
		(color 0 0 0 0)
	)
	(junction
		(at 161.29 241.3)
		(diameter 0)
		(color 0 0 0 0)
	)
	(junction
		(at 210.82 78.74)
		(diameter 0)
		(color 0 0 0 0)
	)
	(junction
		(at 229.87 204.47)
		(diameter 0)
		(color 0 0 0 0)
	)
	(junction
		(at 100.33 231.14)
		(diameter 0)
		(color 0 0 0 0)
	)
	(junction
		(at 210.82 39.37)
		(diameter 0)
		(color 0 0 0 0)
	)
	(junction
		(at 233.68 29.21)
		(diameter 0)
		(color 0 0 0 0)
	)
	(junction
		(at 172.72 29.21)
		(diameter 0)
		(color 0 0 0 0)
	)
	(junction
		(at 248.92 193.04)
		(diameter 0)
		(color 0 0 0 0)
	)
	(junction
		(at 207.01 241.3)
		(diameter 0)
		(color 0 0 0 0)
	)
	(junction
		(at 227.33 55.88)
		(diameter 0)
		(color 0 0 0 0)
	)
	(junction
		(at 226.06 29.21)
		(diameter 0)
		(color 0 0 0 0)
	)
	(junction
		(at 229.87 153.67)
		(diameter 0)
		(color 0 0 0 0)
	)
	(junction
		(at 184.15 223.52)
		(diameter 0)
		(color 0 0 0 0)
	)
	(junction
		(at 229.87 179.07)
		(diameter 0)
		(color 0 0 0 0)
	)
	(junction
		(at 172.72 86.36)
		(diameter 0)
		(color 0 0 0 0)
	)
	(junction
		(at 226.06 68.58)
		(diameter 0)
		(color 0 0 0 0)
	)
	(junction
		(at 233.68 68.58)
		(diameter 0)
		(color 0 0 0 0)
	)
	(junction
		(at 191.77 213.36)
		(diameter 0)
		(color 0 0 0 0)
	)
	(junction
		(at 199.39 213.36)
		(diameter 0)
		(color 0 0 0 0)
	)
	(junction
		(at 184.15 153.67)
		(diameter 0)
		(color 0 0 0 0)
	)
	(junction
		(at 187.96 78.74)
		(diameter 0)
		(color 0 0 0 0)
	)
	(junction
		(at 245.11 213.36)
		(diameter 0)
		(color 0 0 0 0)
	)
	(junction
		(at 229.87 223.52)
		(diameter 0)
		(color 0 0 0 0)
	)
	(junction
		(at 176.53 204.47)
		(diameter 0)
		(color 0 0 0 0)
	)
	(junction
		(at 222.25 204.47)
		(diameter 0)
		(color 0 0 0 0)
	)
	(junction
		(at 226.06 96.52)
		(diameter 0)
		(color 0 0 0 0)
	)
	(junction
		(at 381 246.38)
		(diameter 0)
		(color 0 0 0 0)
	)
	(junction
		(at 176.53 231.14)
		(diameter 0)
		(color 0 0 0 0)
	)
	(junction
		(at 115.57 231.14)
		(diameter 0)
		(color 0 0 0 0)
	)
	(junction
		(at 199.39 241.3)
		(diameter 0)
		(color 0 0 0 0)
	)
	(junction
		(at 157.48 86.36)
		(diameter 0)
		(color 0 0 0 0)
	)
	(junction
		(at 187.96 68.58)
		(diameter 0)
		(color 0 0 0 0)
	)
	(junction
		(at 168.91 194.31)
		(diameter 0)
		(color 0 0 0 0)
	)
	(junction
		(at 187.96 29.21)
		(diameter 0)
		(color 0 0 0 0)
	)
	(junction
		(at 195.58 39.37)
		(diameter 0)
		(color 0 0 0 0)
	)
	(junction
		(at 191.77 223.52)
		(diameter 0)
		(color 0 0 0 0)
	)
	(junction
		(at 184.15 194.31)
		(diameter 0)
		(color 0 0 0 0)
	)
	(junction
		(at 184.15 241.3)
		(diameter 0)
		(color 0 0 0 0)
	)
	(junction
		(at 123.19 241.3)
		(diameter 0)
		(color 0 0 0 0)
	)
	(junction
		(at 210.82 68.58)
		(diameter 0)
		(color 0 0 0 0)
	)
	(junction
		(at 222.25 143.51)
		(diameter 0)
		(color 0 0 0 0)
	)
	(junction
		(at 100.33 241.3)
		(diameter 0)
		(color 0 0 0 0)
	)
	(junction
		(at 161.29 231.14)
		(diameter 0)
		(color 0 0 0 0)
	)
	(junction
		(at 203.2 78.74)
		(diameter 0)
		(color 0 0 0 0)
	)
	(junction
		(at 146.05 213.36)
		(diameter 0)
		(color 0 0 0 0)
	)
	(junction
		(at 237.49 66.04)
		(diameter 0)
		(color 0 0 0 0)
	)
	(junction
		(at 219.71 55.88)
		(diameter 0)
		(color 0 0 0 0)
	)
	(junction
		(at 381 227.33)
		(diameter 0)
		(color 0 0 0 0)
	)
	(junction
		(at 138.43 204.47)
		(diameter 0)
		(color 0 0 0 0)
	)
	(junction
		(at 237.49 231.14)
		(diameter 0)
		(color 0 0 0 0)
	)
	(junction
		(at 180.34 39.37)
		(diameter 0)
		(color 0 0 0 0)
	)
	(junction
		(at 214.63 223.52)
		(diameter 0)
		(color 0 0 0 0)
	)
	(junction
		(at 176.53 223.52)
		(diameter 0)
		(color 0 0 0 0)
	)
	(junction
		(at 203.2 29.21)
		(diameter 0)
		(color 0 0 0 0)
	)
	(junction
		(at 153.67 241.3)
		(diameter 0)
		(color 0 0 0 0)
	)
	(junction
		(at 207.01 153.67)
		(diameter 0)
		(color 0 0 0 0)
	)
	(junction
		(at 207.01 143.51)
		(diameter 0)
		(color 0 0 0 0)
	)
	(junction
		(at 130.81 223.52)
		(diameter 0)
		(color 0 0 0 0)
	)
	(junction
		(at 161.29 223.52)
		(diameter 0)
		(color 0 0 0 0)
	)
	(junction
		(at 191.77 204.47)
		(diameter 0)
		(color 0 0 0 0)
	)
	(junction
		(at 180.34 78.74)
		(diameter 0)
		(color 0 0 0 0)
	)
	(junction
		(at 214.63 143.51)
		(diameter 0)
		(color 0 0 0 0)
	)
	(junction
		(at 199.39 194.31)
		(diameter 0)
		(color 0 0 0 0)
	)
	(junction
		(at 176.53 241.3)
		(diameter 0)
		(color 0 0 0 0)
	)
	(junction
		(at 214.63 171.45)
		(diameter 0)
		(color 0 0 0 0)
	)
	(junction
		(at 153.67 194.31)
		(diameter 0)
		(color 0 0 0 0)
	)
	(junction
		(at 214.63 204.47)
		(diameter 0)
		(color 0 0 0 0)
	)
	(junction
		(at 123.19 231.14)
		(diameter 0)
		(color 0 0 0 0)
	)
	(junction
		(at 195.58 78.74)
		(diameter 0)
		(color 0 0 0 0)
	)
	(junction
		(at 227.33 45.72)
		(diameter 0)
		(color 0 0 0 0)
	)
	(junction
		(at 161.29 213.36)
		(diameter 0)
		(color 0 0 0 0)
	)
	(junction
		(at 214.63 231.14)
		(diameter 0)
		(color 0 0 0 0)
	)
	(junction
		(at 146.05 231.14)
		(diameter 0)
		(color 0 0 0 0)
	)
	(junction
		(at 146.05 194.31)
		(diameter 0)
		(color 0 0 0 0)
	)
	(junction
		(at 149.86 68.58)
		(diameter 0)
		(color 0 0 0 0)
	)
	(junction
		(at 168.91 231.14)
		(diameter 0)
		(color 0 0 0 0)
	)
	(junction
		(at 218.44 29.21)
		(diameter 0)
		(color 0 0 0 0)
	)
	(junction
		(at 218.44 96.52)
		(diameter 0)
		(color 0 0 0 0)
	)
	(junction
		(at 222.25 223.52)
		(diameter 0)
		(color 0 0 0 0)
	)
	(junction
		(at 172.72 96.52)
		(diameter 0)
		(color 0 0 0 0)
	)
	(junction
		(at 165.1 78.74)
		(diameter 0)
		(color 0 0 0 0)
	)
	(junction
		(at 226.06 86.36)
		(diameter 0)
		(color 0 0 0 0)
	)
	(junction
		(at 207.01 223.52)
		(diameter 0)
		(color 0 0 0 0)
	)
	(junction
		(at 115.57 241.3)
		(diameter 0)
		(color 0 0 0 0)
	)
	(junction
		(at 138.43 194.31)
		(diameter 0)
		(color 0 0 0 0)
	)
	(junction
		(at 161.29 204.47)
		(diameter 0)
		(color 0 0 0 0)
	)
	(junction
		(at 153.67 213.36)
		(diameter 0)
		(color 0 0 0 0)
	)
	(junction
		(at 214.63 194.31)
		(diameter 0)
		(color 0 0 0 0)
	)
	(junction
		(at 184.15 204.47)
		(diameter 0)
		(color 0 0 0 0)
	)
	(junction
		(at 222.25 231.14)
		(diameter 0)
		(color 0 0 0 0)
	)
	(junction
		(at 130.81 241.3)
		(diameter 0)
		(color 0 0 0 0)
	)
	(junction
		(at 229.87 143.51)
		(diameter 0)
		(color 0 0 0 0)
	)
	(junction
		(at 138.43 223.52)
		(diameter 0)
		(color 0 0 0 0)
	)
	(junction
		(at 229.87 231.14)
		(diameter 0)
		(color 0 0 0 0)
	)
	(junction
		(at 229.87 213.36)
		(diameter 0)
		(color 0 0 0 0)
	)
	(junction
		(at 207.01 204.47)
		(diameter 0)
		(color 0 0 0 0)
	)
	(junction
		(at 214.63 241.3)
		(diameter 0)
		(color 0 0 0 0)
	)
	(junction
		(at 207.01 231.14)
		(diameter 0)
		(color 0 0 0 0)
	)
	(junction
		(at 146.05 241.3)
		(diameter 0)
		(color 0 0 0 0)
	)
	(junction
		(at 237.49 213.36)
		(diameter 0)
		(color 0 0 0 0)
	)
	(junction
		(at 165.1 96.52)
		(diameter 0)
		(color 0 0 0 0)
	)
	(junction
		(at 149.86 86.36)
		(diameter 0)
		(color 0 0 0 0)
	)
	(junction
		(at 168.91 241.3)
		(diameter 0)
		(color 0 0 0 0)
	)
	(junction
		(at 210.82 86.36)
		(diameter 0)
		(color 0 0 0 0)
	)
	(junction
		(at 146.05 204.47)
		(diameter 0)
		(color 0 0 0 0)
	)
	(junction
		(at 381 231.14)
		(diameter 0)
		(color 0 0 0 0)
	)
	(junction
		(at 229.87 161.29)
		(diameter 0)
		(color 0 0 0 0)
	)
	(junction
		(at 214.63 161.29)
		(diameter 0)
		(color 0 0 0 0)
	)
	(junction
		(at 199.39 204.47)
		(diameter 0)
		(color 0 0 0 0)
	)
	(junction
		(at 157.48 39.37)
		(diameter 0)
		(color 0 0 0 0)
	)
	(junction
		(at 195.58 86.36)
		(diameter 0)
		(color 0 0 0 0)
	)
	(junction
		(at 218.44 78.74)
		(diameter 0)
		(color 0 0 0 0)
	)
	(junction
		(at 191.77 194.31)
		(diameter 0)
		(color 0 0 0 0)
	)
	(junction
		(at 176.53 213.36)
		(diameter 0)
		(color 0 0 0 0)
	)
	(junction
		(at 233.68 86.36)
		(diameter 0)
		(color 0 0 0 0)
	)
	(junction
		(at 203.2 96.52)
		(diameter 0)
		(color 0 0 0 0)
	)
	(junction
		(at 199.39 231.14)
		(diameter 0)
		(color 0 0 0 0)
	)
	(junction
		(at 123.19 223.52)
		(diameter 0)
		(color 0 0 0 0)
	)
	(junction
		(at 184.15 213.36)
		(diameter 0)
		(color 0 0 0 0)
	)
	(junction
		(at 218.44 68.58)
		(diameter 0)
		(color 0 0 0 0)
	)
	(junction
		(at 214.63 213.36)
		(diameter 0)
		(color 0 0 0 0)
	)
	(junction
		(at 176.53 194.31)
		(diameter 0)
		(color 0 0 0 0)
	)
	(junction
		(at 191.77 241.3)
		(diameter 0)
		(color 0 0 0 0)
	)
	(junction
		(at 157.48 96.52)
		(diameter 0)
		(color 0 0 0 0)
	)
	(junction
		(at 222.25 161.29)
		(diameter 0)
		(color 0 0 0 0)
	)
	(junction
		(at 187.96 86.36)
		(diameter 0)
		(color 0 0 0 0)
	)
	(junction
		(at 180.34 96.52)
		(diameter 0)
		(color 0 0 0 0)
	)
	(junction
		(at 165.1 68.58)
		(diameter 0)
		(color 0 0 0 0)
	)
	(junction
		(at 229.87 171.45)
		(diameter 0)
		(color 0 0 0 0)
	)
	(junction
		(at 237.49 143.51)
		(diameter 0)
		(color 0 0 0 0)
	)
	(junction
		(at 130.81 213.36)
		(diameter 0)
		(color 0 0 0 0)
	)
	(junction
		(at 153.67 204.47)
		(diameter 0)
		(color 0 0 0 0)
	)
	(junction
		(at 187.96 39.37)
		(diameter 0)
		(color 0 0 0 0)
	)
	(junction
		(at 184.15 231.14)
		(diameter 0)
		(color 0 0 0 0)
	)
	(junction
		(at 237.49 161.29)
		(diameter 0)
		(color 0 0 0 0)
	)
	(junction
		(at 195.58 29.21)
		(diameter 0)
		(color 0 0 0 0)
	)
	(junction
		(at 123.19 213.36)
		(diameter 0)
		(color 0 0 0 0)
	)
	(junction
		(at 203.2 68.58)
		(diameter 0)
		(color 0 0 0 0)
	)
	(junction
		(at 222.25 153.67)
		(diameter 0)
		(color 0 0 0 0)
	)
	(junction
		(at 138.43 213.36)
		(diameter 0)
		(color 0 0 0 0)
	)
	(junction
		(at 218.44 86.36)
		(diameter 0)
		(color 0 0 0 0)
	)
	(junction
		(at 199.39 143.51)
		(diameter 0)
		(color 0 0 0 0)
	)
	(junction
		(at 130.81 231.14)
		(diameter 0)
		(color 0 0 0 0)
	)
	(junction
		(at 168.91 204.47)
		(diameter 0)
		(color 0 0 0 0)
	)
	(junction
		(at 207.01 194.31)
		(diameter 0)
		(color 0 0 0 0)
	)
	(junction
		(at 191.77 231.14)
		(diameter 0)
		(color 0 0 0 0)
	)
	(junction
		(at 180.34 29.21)
		(diameter 0)
		(color 0 0 0 0)
	)
	(junction
		(at 203.2 86.36)
		(diameter 0)
		(color 0 0 0 0)
	)
	(junction
		(at 222.25 241.3)
		(diameter 0)
		(color 0 0 0 0)
	)
	(junction
		(at 195.58 68.58)
		(diameter 0)
		(color 0 0 0 0)
	)
	(junction
		(at 153.67 223.52)
		(diameter 0)
		(color 0 0 0 0)
	)
	(junction
		(at 214.63 153.67)
		(diameter 0)
		(color 0 0 0 0)
	)
	(junction
		(at 222.25 194.31)
		(diameter 0)
		(color 0 0 0 0)
	)
	(no_connect
		(at 250.19 186.69)
	)
	(wire
		(pts
			(xy 191.77 196.85) (xy 191.77 194.31)
		)
		(stroke
			(width 0)
			(type default)
		)
	)
	(wire
		(pts
			(xy 229.87 180.34) (xy 229.87 179.07)
		)
		(stroke
			(width 0)
			(type default)
		)
	)
	(wire
		(pts
			(xy 130.81 213.36) (xy 138.43 213.36)
		)
		(stroke
			(width 0)
			(type default)
		)
	)
	(wire
		(pts
			(xy 191.77 223.52) (xy 184.15 223.52)
		)
		(stroke
			(width 0)
			(type default)
		)
	)
	(wire
		(pts
			(xy 149.86 76.2) (xy 149.86 78.74)
		)
		(stroke
			(width 0)
			(type default)
		)
	)
	(wire
		(pts
			(xy 229.87 179.07) (xy 250.19 179.07)
		)
		(stroke
			(width 0)
			(type default)
		)
	)
	(wire
		(pts
			(xy 191.77 241.3) (xy 199.39 241.3)
		)
		(stroke
			(width 0)
			(type default)
		)
	)
	(wire
		(pts
			(xy 229.87 241.3) (xy 229.87 238.76)
		)
		(stroke
			(width 0)
			(type default)
		)
	)
	(wire
		(pts
			(xy 227.33 48.26) (xy 227.33 45.72)
		)
		(stroke
			(width 0)
			(type default)
		)
	)
	(wire
		(pts
			(xy 138.43 231.14) (xy 138.43 233.68)
		)
		(stroke
			(width 0)
			(type default)
		)
	)
	(wire
		(pts
			(xy 222.25 171.45) (xy 214.63 171.45)
		)
		(stroke
			(width 0)
			(type default)
		)
	)
	(wire
		(pts
			(xy 226.06 86.36) (xy 226.06 88.9)
		)
		(stroke
			(width 0)
			(type default)
		)
	)
	(wire
		(pts
			(xy 381 231.14) (xy 368.3 231.14)
		)
		(stroke
			(width 0)
			(type default)
		)
	)
	(wire
		(pts
			(xy 227.33 45.72) (xy 219.71 45.72)
		)
		(stroke
			(width 0)
			(type default)
		)
	)
	(wire
		(pts
			(xy 381 250.19) (xy 368.3 250.19)
		)
		(stroke
			(width 0)
			(type default)
		)
	)
	(wire
		(pts
			(xy 250.19 184.15) (xy 245.11 184.15)
		)
		(stroke
			(width 0)
			(type default)
		)
	)
	(wire
		(pts
			(xy 130.81 213.36) (xy 123.19 213.36)
		)
		(stroke
			(width 0)
			(type default)
		)
	)
	(wire
		(pts
			(xy 237.49 213.36) (xy 245.11 213.36)
		)
		(stroke
			(width 0)
			(type default)
		)
	)
	(wire
		(pts
			(xy 214.63 231.14) (xy 222.25 231.14)
		)
		(stroke
			(width 0)
			(type default)
		)
	)
	(wire
		(pts
			(xy 199.39 143.51) (xy 199.39 146.05)
		)
		(stroke
			(width 0)
			(type default)
		)
	)
	(wire
		(pts
			(xy 222.25 231.14) (xy 229.87 231.14)
		)
		(stroke
			(width 0)
			(type default)
		)
	)
	(wire
		(pts
			(xy 176.53 241.3) (xy 176.53 238.76)
		)
		(stroke
			(width 0)
			(type default)
		)
	)
	(wire
		(pts
			(xy 184.15 143.51) (xy 184.15 146.05)
		)
		(stroke
			(width 0)
			(type default)
		)
	)
	(wire
		(pts
			(xy 138.43 194.31) (xy 146.05 194.31)
		)
		(stroke
			(width 0)
			(type default)
		)
	)
	(wire
		(pts
			(xy 203.2 68.58) (xy 210.82 68.58)
		)
		(stroke
			(width 0)
			(type default)
		)
	)
	(wire
		(pts
			(xy 199.39 213.36) (xy 207.01 213.36)
		)
		(stroke
			(width 0)
			(type default)
		)
	)
	(wire
		(pts
			(xy 187.96 68.58) (xy 195.58 68.58)
		)
		(stroke
			(width 0)
			(type default)
		)
	)
	(wire
		(pts
			(xy 195.58 29.21) (xy 195.58 31.75)
		)
		(stroke
			(width 0)
			(type default)
		)
	)
	(wire
		(pts
			(xy 184.15 142.24) (xy 184.15 143.51)
		)
		(stroke
			(width 0)
			(type default)
		)
	)
	(wire
		(pts
			(xy 153.67 194.31) (xy 161.29 194.31)
		)
		(stroke
			(width 0)
			(type default)
		)
	)
	(wire
		(pts
			(xy 218.44 39.37) (xy 218.44 36.83)
		)
		(stroke
			(width 0)
			(type default)
		)
	)
	(wire
		(pts
			(xy 161.29 238.76) (xy 161.29 241.3)
		)
		(stroke
			(width 0)
			(type default)
		)
	)
	(wire
		(pts
			(xy 168.91 194.31) (xy 176.53 194.31)
		)
		(stroke
			(width 0)
			(type default)
		)
	)
	(wire
		(pts
			(xy 123.19 223.52) (xy 123.19 224.79)
		)
		(stroke
			(width 0)
			(type default)
		)
	)
	(wire
		(pts
			(xy 214.63 161.29) (xy 222.25 161.29)
		)
		(stroke
			(width 0)
			(type default)
		)
	)
	(wire
		(pts
			(xy 233.68 29.21) (xy 247.65 29.21)
		)
		(stroke
			(width 0)
			(type default)
		)
	)
	(wire
		(pts
			(xy 139.7 68.58) (xy 149.86 68.58)
		)
		(stroke
			(width 0)
			(type default)
		)
	)
	(wire
		(pts
			(xy 381 227.33) (xy 381 231.14)
		)
		(stroke
			(width 0)
			(type default)
		)
	)
	(wire
		(pts
			(xy 214.63 160.02) (xy 214.63 161.29)
		)
		(stroke
			(width 0)
			(type default)
		)
	)
	(wire
		(pts
			(xy 165.1 29.21) (xy 172.72 29.21)
		)
		(stroke
			(width 0)
			(type default)
		)
	)
	(wire
		(pts
			(xy 229.87 223.52) (xy 222.25 223.52)
		)
		(stroke
			(width 0)
			(type default)
		)
	)
	(wire
		(pts
			(xy 187.96 29.21) (xy 195.58 29.21)
		)
		(stroke
			(width 0)
			(type default)
		)
	)
	(wire
		(pts
			(xy 172.72 76.2) (xy 172.72 78.74)
		)
		(stroke
			(width 0)
			(type default)
		)
	)
	(wire
		(pts
			(xy 397.51 250.19) (xy 381 250.19)
		)
		(stroke
			(width 0)
			(type default)
		)
	)
	(wire
		(pts
			(xy 367.03 238.76) (xy 367.03 241.3)
		)
		(stroke
			(width 0)
			(type default)
		)
	)
	(wire
		(pts
			(xy 210.82 78.74) (xy 218.44 78.74)
		)
		(stroke
			(width 0)
			(type default)
		)
	)
	(wire
		(pts
			(xy 397.51 224.79) (xy 397.51 231.14)
		)
		(stroke
			(width 0)
			(type default)
		)
	)
	(wire
		(pts
			(xy 153.67 204.47) (xy 153.67 201.93)
		)
		(stroke
			(width 0)
			(type default)
		)
	)
	(wire
		(pts
			(xy 218.44 78.74) (xy 218.44 76.2)
		)
		(stroke
			(width 0)
			(type default)
		)
	)
	(wire
		(pts
			(xy 176.53 213.36) (xy 176.53 215.9)
		)
		(stroke
			(width 0)
			(type default)
		)
	)
	(wire
		(pts
			(xy 100.33 231.14) (xy 100.33 233.68)
		)
		(stroke
			(width 0)
			(type default)
		)
	)
	(wire
		(pts
			(xy 214.63 204.47) (xy 214.63 201.93)
		)
		(stroke
			(width 0)
			(type default)
		)
	)
	(wire
		(pts
			(xy 168.91 223.52) (xy 168.91 220.98)
		)
		(stroke
			(width 0)
			(type default)
		)
	)
	(wire
		(pts
			(xy 214.63 146.05) (xy 214.63 143.51)
		)
		(stroke
			(width 0)
			(type default)
		)
	)
	(wire
		(pts
			(xy 130.81 213.36) (xy 130.81 215.9)
		)
		(stroke
			(width 0)
			(type default)
		)
	)
	(wire
		(pts
			(xy 203.2 71.12) (xy 203.2 68.58)
		)
		(stroke
			(width 0)
			(type default)
		)
	)
	(wire
		(pts
			(xy 195.58 93.98) (xy 195.58 96.52)
		)
		(stroke
			(width 0)
			(type default)
		)
	)
	(wire
		(pts
			(xy 214.63 204.47) (xy 222.25 204.47)
		)
		(stroke
			(width 0)
			(type default)
		)
	)
	(wire
		(pts
			(xy 368.3 224.79) (xy 369.57 224.79)
		)
		(stroke
			(width 0)
			(type default)
		)
	)
	(wire
		(pts
			(xy 165.1 96.52) (xy 165.1 93.98)
		)
		(stroke
			(width 0)
			(type default)
		)
	)
	(wire
		(pts
			(xy 191.77 194.31) (xy 199.39 194.31)
		)
		(stroke
			(width 0)
			(type default)
		)
	)
	(wire
		(pts
			(xy 184.15 194.31) (xy 184.15 196.85)
		)
		(stroke
			(width 0)
			(type default)
		)
	)
	(wire
		(pts
			(xy 176.53 223.52) (xy 176.53 220.98)
		)
		(stroke
			(width 0)
			(type default)
		)
	)
	(wire
		(pts
			(xy 157.48 78.74) (xy 165.1 78.74)
		)
		(stroke
			(width 0)
			(type default)
		)
	)
	(wire
		(pts
			(xy 180.34 93.98) (xy 180.34 96.52)
		)
		(stroke
			(width 0)
			(type default)
		)
	)
	(wire
		(pts
			(xy 214.63 143.51) (xy 222.25 143.51)
		)
		(stroke
			(width 0)
			(type default)
		)
	)
	(wire
		(pts
			(xy 146.05 223.52) (xy 146.05 220.98)
		)
		(stroke
			(width 0)
			(type default)
		)
	)
	(wire
		(pts
			(xy 222.25 163.83) (xy 222.25 161.29)
		)
		(stroke
			(width 0)
			(type default)
		)
	)
	(wire
		(pts
			(xy 191.77 223.52) (xy 191.77 220.98)
		)
		(stroke
			(width 0)
			(type default)
		)
	)
	(wire
		(pts
			(xy 161.29 194.31) (xy 168.91 194.31)
		)
		(stroke
			(width 0)
			(type default)
		)
	)
	(polyline
		(pts
			(xy 350.52 209.55) (xy 350.52 252.73)
		)
		(stroke
			(width 0)
			(type default)
		)
	)
	(wire
		(pts
			(xy 130.81 241.3) (xy 130.81 238.76)
		)
		(stroke
			(width 0)
			(type default)
		)
	)
	(wire
		(pts
			(xy 146.05 241.3) (xy 153.67 241.3)
		)
		(stroke
			(width 0)
			(type default)
		)
	)
	(wire
		(pts
			(xy 187.96 96.52) (xy 187.96 93.98)
		)
		(stroke
			(width 0)
			(type default)
		)
	)
	(wire
		(pts
			(xy 214.63 241.3) (xy 222.25 241.3)
		)
		(stroke
			(width 0)
			(type default)
		)
	)
	(wire
		(pts
			(xy 233.68 68.58) (xy 248.92 68.58)
		)
		(stroke
			(width 0)
			(type default)
		)
	)
	(wire
		(pts
			(xy 195.58 78.74) (xy 195.58 76.2)
		)
		(stroke
			(width 0)
			(type default)
		)
	)
	(wire
		(pts
			(xy 149.86 71.12) (xy 149.86 68.58)
		)
		(stroke
			(width 0)
			(type default)
		)
	)
	(wire
		(pts
			(xy 191.77 241.3) (xy 191.77 238.76)
		)
		(stroke
			(width 0)
			(type default)
		)
	)
	(wire
		(pts
			(xy 191.77 204.47) (xy 184.15 204.47)
		)
		(stroke
			(width 0)
			(type default)
		)
	)
	(wire
		(pts
			(xy 222.25 143.51) (xy 222.25 146.05)
		)
		(stroke
			(width 0)
			(type default)
		)
	)
	(wire
		(pts
			(xy 138.43 231.14) (xy 146.05 231.14)
		)
		(stroke
			(width 0)
			(type default)
		)
	)
	(wire
		(pts
			(xy 203.2 36.83) (xy 203.2 39.37)
		)
		(stroke
			(width 0)
			(type default)
		)
	)
	(wire
		(pts
			(xy 222.25 213.36) (xy 229.87 213.36)
		)
		(stroke
			(width 0)
			(type default)
		)
	)
	(wire
		(pts
			(xy 237.49 171.45) (xy 237.49 168.91)
		)
		(stroke
			(width 0)
			(type default)
		)
	)
	(wire
		(pts
			(xy 115.57 238.76) (xy 115.57 241.3)
		)
		(stroke
			(width 0)
			(type default)
		)
	)
	(wire
		(pts
			(xy 229.87 194.31) (xy 229.87 196.85)
		)
		(stroke
			(width 0)
			(type default)
		)
	)
	(wire
		(pts
			(xy 195.58 39.37) (xy 203.2 39.37)
		)
		(stroke
			(width 0)
			(type default)
		)
	)
	(wire
		(pts
			(xy 229.87 231.14) (xy 237.49 231.14)
		)
		(stroke
			(width 0)
			(type default)
		)
	)
	(wire
		(pts
			(xy 226.06 96.52) (xy 226.06 93.98)
		)
		(stroke
			(width 0)
			(type default)
		)
	)
	(wire
		(pts
			(xy 153.67 223.52) (xy 161.29 223.52)
		)
		(stroke
			(width 0)
			(type default)
		)
	)
	(wire
		(pts
			(xy 218.44 78.74) (xy 226.06 78.74)
		)
		(stroke
			(width 0)
			(type default)
		)
	)
	(wire
		(pts
			(xy 199.39 231.14) (xy 207.01 231.14)
		)
		(stroke
			(width 0)
			(type default)
		)
	)
	(wire
		(pts
			(xy 233.68 88.9) (xy 233.68 86.36)
		)
		(stroke
			(width 0)
			(type default)
		)
	)
	(wire
		(pts
			(xy 218.44 86.36) (xy 226.06 86.36)
		)
		(stroke
			(width 0)
			(type default)
		)
	)
	(wire
		(pts
			(xy 139.7 85.09) (xy 139.7 86.36)
		)
		(stroke
			(width 0)
			(type default)
		)
	)
	(wire
		(pts
			(xy 222.25 201.93) (xy 222.25 204.47)
		)
		(stroke
			(width 0)
			(type default)
		)
	)
	(wire
		(pts
			(xy 165.1 78.74) (xy 165.1 76.2)
		)
		(stroke
			(width 0)
			(type default)
		)
	)
	(wire
		(pts
			(xy 207.01 204.47) (xy 207.01 201.93)
		)
		(stroke
			(width 0)
			(type default)
		)
	)
	(wire
		(pts
			(xy 115.57 231.14) (xy 123.19 231.14)
		)
		(stroke
			(width 0)
			(type default)
		)
	)
	(wire
		(pts
			(xy 237.49 163.83) (xy 237.49 161.29)
		)
		(stroke
			(width 0)
			(type default)
		)
	)
	(wire
		(pts
			(xy 187.96 39.37) (xy 187.96 36.83)
		)
		(stroke
			(width 0)
			(type default)
		)
	)
	(wire
		(pts
			(xy 233.68 39.37) (xy 233.68 36.83)
		)
		(stroke
			(width 0)
			(type default)
		)
	)
	(wire
		(pts
			(xy 229.87 241.3) (xy 222.25 241.3)
		)
		(stroke
			(width 0)
			(type default)
		)
	)
	(wire
		(pts
			(xy 218.44 93.98) (xy 218.44 96.52)
		)
		(stroke
			(width 0)
			(type default)
		)
	)
	(wire
		(pts
			(xy 237.49 194.31) (xy 237.49 196.85)
		)
		(stroke
			(width 0)
			(type default)
		)
	)
	(wire
		(pts
			(xy 153.67 231.14) (xy 161.29 231.14)
		)
		(stroke
			(width 0)
			(type default)
		)
	)
	(wire
		(pts
			(xy 138.43 194.31) (xy 138.43 196.85)
		)
		(stroke
			(width 0)
			(type default)
		)
	)
	(wire
		(pts
			(xy 184.15 204.47) (xy 176.53 204.47)
		)
		(stroke
			(width 0)
			(type default)
		)
	)
	(wire
		(pts
			(xy 237.49 223.52) (xy 237.49 220.98)
		)
		(stroke
			(width 0)
			(type default)
		)
	)
	(wire
		(pts
			(xy 107.95 241.3) (xy 100.33 241.3)
		)
		(stroke
			(width 0)
			(type default)
		)
	)
	(wire
		(pts
			(xy 207.01 213.36) (xy 214.63 213.36)
		)
		(stroke
			(width 0)
			(type default)
		)
	)
	(wire
		(pts
			(xy 100.33 229.87) (xy 100.33 231.14)
		)
		(stroke
			(width 0)
			(type default)
		)
	)
	(wire
		(pts
			(xy 397.51 231.14) (xy 381 231.14)
		)
		(stroke
			(width 0)
			(type default)
		)
	)
	(wire
		(pts
			(xy 161.29 231.14) (xy 161.29 233.68)
		)
		(stroke
			(width 0)
			(type default)
		)
	)
	(wire
		(pts
			(xy 184.15 204.47) (xy 184.15 201.93)
		)
		(stroke
			(width 0)
			(type default)
		)
	)
	(wire
		(pts
			(xy 115.57 241.3) (xy 123.19 241.3)
		)
		(stroke
			(width 0)
			(type default)
		)
	)
	(wire
		(pts
			(xy 229.87 241.3) (xy 237.49 241.3)
		)
		(stroke
			(width 0)
			(type default)
		)
	)
	(wire
		(pts
			(xy 237.49 66.04) (xy 248.92 66.04)
		)
		(stroke
			(width 0)
			(type default)
		)
	)
	(wire
		(pts
			(xy 187.96 76.2) (xy 187.96 78.74)
		)
		(stroke
			(width 0)
			(type default)
		)
	)
	(wire
		(pts
			(xy 383.54 224.79) (xy 383.54 219.71)
		)
		(stroke
			(width 0)
			(type default)
		)
	)
	(wire
		(pts
			(xy 203.2 29.21) (xy 210.82 29.21)
		)
		(stroke
			(width 0)
			(type default)
		)
	)
	(wire
		(pts
			(xy 195.58 86.36) (xy 203.2 86.36)
		)
		(stroke
			(width 0)
			(type default)
		)
	)
	(wire
		(pts
			(xy 157.48 29.21) (xy 157.48 31.75)
		)
		(stroke
			(width 0)
			(type default)
		)
	)
	(wire
		(pts
			(xy 214.63 153.67) (xy 207.01 153.67)
		)
		(stroke
			(width 0)
			(type default)
		)
	)
	(wire
		(pts
			(xy 226.06 86.36) (xy 233.68 86.36)
		)
		(stroke
			(width 0)
			(type default)
		)
	)
	(wire
		(pts
			(xy 187.96 96.52) (xy 195.58 96.52)
		)
		(stroke
			(width 0)
			(type default)
		)
	)
	(wire
		(pts
			(xy 176.53 231.14) (xy 176.53 233.68)
		)
		(stroke
			(width 0)
			(type default)
		)
	)
	(wire
		(pts
			(xy 229.87 204.47) (xy 222.25 204.47)
		)
		(stroke
			(width 0)
			(type default)
		)
	)
	(wire
		(pts
			(xy 146.05 241.3) (xy 146.05 238.76)
		)
		(stroke
			(width 0)
			(type default)
		)
	)
	(wire
		(pts
			(xy 369.57 222.25) (xy 367.03 222.25)
		)
		(stroke
			(width 0)
			(type default)
		)
	)
	(wire
		(pts
			(xy 172.72 86.36) (xy 180.34 86.36)
		)
		(stroke
			(width 0)
			(type default)
		)
	)
	(wire
		(pts
			(xy 381 241.3) (xy 381 246.38)
		)
		(stroke
			(width 0)
			(type default)
		)
	)
	(wire
		(pts
			(xy 180.34 71.12) (xy 180.34 68.58)
		)
		(stroke
			(width 0)
			(type default)
		)
	)
	(wire
		(pts
			(xy 172.72 96.52) (xy 180.34 96.52)
		)
		(stroke
			(width 0)
			(type default)
		)
	)
	(wire
		(pts
			(xy 195.58 68.58) (xy 195.58 71.12)
		)
		(stroke
			(width 0)
			(type default)
		)
	)
	(wire
		(pts
			(xy 229.87 161.29) (xy 229.87 163.83)
		)
		(stroke
			(width 0)
			(type default)
		)
	)
	(wire
		(pts
			(xy 184.15 241.3) (xy 184.15 238.76)
		)
		(stroke
			(width 0)
			(type default)
		)
	)
	(wire
		(pts
			(xy 172.72 39.37) (xy 180.34 39.37)
		)
		(stroke
			(width 0)
			(type default)
		)
	)
	(wire
		(pts
			(xy 218.44 96.52) (xy 226.06 96.52)
		)
		(stroke
			(width 0)
			(type default)
		)
	)
	(wire
		(pts
			(xy 184.15 223.52) (xy 176.53 223.52)
		)
		(stroke
			(width 0)
			(type default)
		)
	)
	(wire
		(pts
			(xy 215.9 66.04) (xy 224.79 66.04)
		)
		(stroke
			(width 0)
			(type default)
		)
	)
	(wire
		(pts
			(xy 199.39 201.93) (xy 199.39 204.47)
		)
		(stroke
			(width 0)
			(type default)
		)
	)
	(wire
		(pts
			(xy 247.65 59.69) (xy 248.92 59.69)
		)
		(stroke
			(width 0)
			(type default)
		)
	)
	(wire
		(pts
			(xy 233.68 31.75) (xy 233.68 29.21)
		)
		(stroke
			(width 0)
			(type default)
		)
	)
	(wire
		(pts
			(xy 146.05 204.47) (xy 138.43 204.47)
		)
		(stroke
			(width 0)
			(type default)
		)
	)
	(wire
		(pts
			(xy 218.44 29.21) (xy 218.44 31.75)
		)
		(stroke
			(width 0)
			(type default)
		)
	)
	(wire
		(pts
			(xy 245.11 184.15) (xy 245.11 213.36)
		)
		(stroke
			(width 0)
			(type default)
		)
	)
	(wire
		(pts
			(xy 195.58 96.52) (xy 203.2 96.52)
		)
		(stroke
			(width 0)
			(type default)
		)
	)
	(wire
		(pts
			(xy 207.01 194.31) (xy 214.63 194.31)
		)
		(stroke
			(width 0)
			(type default)
		)
	)
	(wire
		(pts
			(xy 207.01 223.52) (xy 214.63 223.52)
		)
		(stroke
			(width 0)
			(type default)
		)
	)
	(wire
		(pts
			(xy 149.86 39.37) (xy 149.86 40.64)
		)
		(stroke
			(width 0)
			(type default)
		)
	)
	(wire
		(pts
			(xy 360.68 227.33) (xy 360.68 224.79)
		)
		(stroke
			(width 0)
			(type default)
		)
	)
	(wire
		(pts
			(xy 226.06 71.12) (xy 226.06 68.58)
		)
		(stroke
			(width 0)
			(type default)
		)
	)
	(wire
		(pts
			(xy 115.57 231.14) (xy 115.57 233.68)
		)
		(stroke
			(width 0)
			(type default)
		)
	)
	(wire
		(pts
			(xy 214.63 153.67) (xy 214.63 151.13)
		)
		(stroke
			(width 0)
			(type default)
		)
	)
	(wire
		(pts
			(xy 233.68 96.52) (xy 233.68 93.98)
		)
		(stroke
			(width 0)
			(type default)
		)
	)
	(wire
		(pts
			(xy 226.06 29.21) (xy 226.06 31.75)
		)
		(stroke
			(width 0)
			(type default)
		)
	)
	(wire
		(pts
			(xy 210.82 88.9) (xy 210.82 86.36)
		)
		(stroke
			(width 0)
			(type default)
		)
	)
	(wire
		(pts
			(xy 146.05 213.36) (xy 153.67 213.36)
		)
		(stroke
			(width 0)
			(type default)
		)
	)
	(wire
		(pts
			(xy 168.91 194.31) (xy 168.91 196.85)
		)
		(stroke
			(width 0)
			(type default)
		)
	)
	(wire
		(pts
			(xy 153.67 231.14) (xy 153.67 233.68)
		)
		(stroke
			(width 0)
			(type default)
		)
	)
	(polyline
		(pts
			(xy 350.52 209.55) (xy 406.4 209.55)
		)
		(stroke
			(width 0)
			(type default)
		)
	)
	(wire
		(pts
			(xy 153.67 213.36) (xy 161.29 213.36)
		)
		(stroke
			(width 0)
			(type default)
		)
	)
	(wire
		(pts
			(xy 176.53 204.47) (xy 176.53 201.93)
		)
		(stroke
			(width 0)
			(type default)
		)
	)
	(wire
		(pts
			(xy 233.68 45.72) (xy 245.11 45.72)
		)
		(stroke
			(width 0)
			(type default)
		)
	)
	(wire
		(pts
			(xy 187.96 78.74) (xy 195.58 78.74)
		)
		(stroke
			(width 0)
			(type default)
		)
	)
	(wire
		(pts
			(xy 138.43 238.76) (xy 138.43 241.3)
		)
		(stroke
			(width 0)
			(type default)
		)
	)
	(wire
		(pts
			(xy 247.65 29.21) (xy 247.65 59.69)
		)
		(stroke
			(width 0)
			(type default)
		)
	)
	(wire
		(pts
			(xy 222.25 233.68) (xy 222.25 231.14)
		)
		(stroke
			(width 0)
			(type default)
		)
	)
	(wire
		(pts
			(xy 123.19 241.3) (xy 123.19 238.76)
		)
		(stroke
			(width 0)
			(type default)
		)
	)
	(wire
		(pts
			(xy 203.2 29.21) (xy 203.2 31.75)
		)
		(stroke
			(width 0)
			(type default)
		)
	)
	(wire
		(pts
			(xy 218.44 39.37) (xy 226.06 39.37)
		)
		(stroke
			(width 0)
			(type default)
		)
	)
	(wire
		(pts
			(xy 207.01 241.3) (xy 214.63 241.3)
		)
		(stroke
			(width 0)
			(type default)
		)
	)
	(wire
		(pts
			(xy 248.92 190.5) (xy 248.92 193.04)
		)
		(stroke
			(width 0)
			(type default)
		)
	)
	(wire
		(pts
			(xy 191.77 213.36) (xy 191.77 215.9)
		)
		(stroke
			(width 0)
			(type default)
		)
	)
	(wire
		(pts
			(xy 165.1 68.58) (xy 165.1 71.12)
		)
		(stroke
			(width 0)
			(type default)
		)
	)
	(wire
		(pts
			(xy 237.49 171.45) (xy 229.87 171.45)
		)
		(stroke
			(width 0)
			(type default)
		)
	)
	(wire
		(pts
			(xy 157.48 36.83) (xy 157.48 39.37)
		)
		(stroke
			(width 0)
			(type default)
		)
	)
	(wire
		(pts
			(xy 172.72 29.21) (xy 172.72 31.75)
		)
		(stroke
			(width 0)
			(type default)
		)
	)
	(wire
		(pts
			(xy 237.49 241.3) (xy 237.49 238.76)
		)
		(stroke
			(width 0)
			(type default)
		)
	)
	(wire
		(pts
			(xy 218.44 29.21) (xy 226.06 29.21)
		)
		(stroke
			(width 0)
			(type default)
		)
	)
	(wire
		(pts
			(xy 184.15 231.14) (xy 191.77 231.14)
		)
		(stroke
			(width 0)
			(type default)
		)
	)
	(wire
		(pts
			(xy 226.06 68.58) (xy 233.68 68.58)
		)
		(stroke
			(width 0)
			(type default)
		)
	)
	(wire
		(pts
			(xy 237.49 204.47) (xy 237.49 201.93)
		)
		(stroke
			(width 0)
			(type default)
		)
	)
	(wire
		(pts
			(xy 165.1 68.58) (xy 172.72 68.58)
		)
		(stroke
			(width 0)
			(type default)
		)
	)
	(wire
		(pts
			(xy 149.86 36.83) (xy 149.86 39.37)
		)
		(stroke
			(width 0)
			(type default)
		)
	)
	(wire
		(pts
			(xy 172.72 78.74) (xy 180.34 78.74)
		)
		(stroke
			(width 0)
			(type default)
		)
	)
	(wire
		(pts
			(xy 168.91 223.52) (xy 161.29 223.52)
		)
		(stroke
			(width 0)
			(type default)
		)
	)
	(wire
		(pts
			(xy 237.49 231.14) (xy 245.11 231.14)
		)
		(stroke
			(width 0)
			(type default)
		)
	)
	(wire
		(pts
			(xy 248.92 193.04) (xy 248.92 194.31)
		)
		(stroke
			(width 0)
			(type default)
		)
	)
	(wire
		(pts
			(xy 146.05 223.52) (xy 153.67 223.52)
		)
		(stroke
			(width 0)
			(type default)
		)
	)
	(wire
		(pts
			(xy 203.2 86.36) (xy 203.2 88.9)
		)
		(stroke
			(width 0)
			(type default)
		)
	)
	(wire
		(pts
			(xy 229.87 161.29) (xy 237.49 161.29)
		)
		(stroke
			(width 0)
			(type default)
		)
	)
	(wire
		(pts
			(xy 165.1 29.21) (xy 165.1 31.75)
		)
		(stroke
			(width 0)
			(type default)
		)
	)
	(wire
		(pts
			(xy 180.34 96.52) (xy 187.96 96.52)
		)
		(stroke
			(width 0)
			(type default)
		)
	)
	(wire
		(pts
			(xy 210.82 76.2) (xy 210.82 78.74)
		)
		(stroke
			(width 0)
			(type default)
		)
	)
	(wire
		(pts
			(xy 165.1 96.52) (xy 172.72 96.52)
		)
		(stroke
			(width 0)
			(type default)
		)
	)
	(wire
		(pts
			(xy 210.82 31.75) (xy 210.82 29.21)
		)
		(stroke
			(width 0)
			(type default)
		)
	)
	(wire
		(pts
			(xy 199.39 238.76) (xy 199.39 241.3)
		)
		(stroke
			(width 0)
			(type default)
		)
	)
	(wire
		(pts
			(xy 187.96 39.37) (xy 195.58 39.37)
		)
		(stroke
			(width 0)
			(type default)
		)
	)
	(wire
		(pts
			(xy 368.3 231.14) (xy 368.3 224.79)
		)
		(stroke
			(width 0)
			(type default)
		)
	)
	(wire
		(pts
			(xy 161.29 220.98) (xy 161.29 223.52)
		)
		(stroke
			(width 0)
			(type default)
		)
	)
	(wire
		(pts
			(xy 157.48 68.58) (xy 157.48 71.12)
		)
		(stroke
			(width 0)
			(type default)
		)
	)
	(wire
		(pts
			(xy 250.19 173.99) (xy 250.19 143.51)
		)
		(stroke
			(width 0)
			(type default)
		)
	)
	(wire
		(pts
			(xy 369.57 241.3) (xy 367.03 241.3)
		)
		(stroke
			(width 0)
			(type default)
		)
	)
	(wire
		(pts
			(xy 138.43 220.98) (xy 138.43 223.52)
		)
		(stroke
			(width 0)
			(type default)
		)
	)
	(wire
		(pts
			(xy 203.2 39.37) (xy 210.82 39.37)
		)
		(stroke
			(width 0)
			(type default)
		)
	)
	(wire
		(pts
			(xy 214.63 241.3) (xy 214.63 238.76)
		)
		(stroke
			(width 0)
			(type default)
		)
	)
	(wire
		(pts
			(xy 176.53 194.31) (xy 176.53 196.85)
		)
		(stroke
			(width 0)
			(type default)
		)
	)
	(wire
		(pts
			(xy 240.03 181.61) (xy 240.03 194.31)
		)
		(stroke
			(width 0)
			(type default)
		)
	)
	(wire
		(pts
			(xy 214.63 171.45) (xy 214.63 172.72)
		)
		(stroke
			(width 0)
			(type default)
		)
	)
	(wire
		(pts
			(xy 123.19 231.14) (xy 130.81 231.14)
		)
		(stroke
			(width 0)
			(type default)
		)
	)
	(wire
		(pts
			(xy 130.81 231.14) (xy 138.43 231.14)
		)
		(stroke
			(width 0)
			(type default)
		)
	)
	(wire
		(pts
			(xy 229.87 223.52) (xy 229.87 220.98)
		)
		(stroke
			(width 0)
			(type default)
		)
	)
	(wire
		(pts
			(xy 199.39 223.52) (xy 207.01 223.52)
		)
		(stroke
			(width 0)
			(type default)
		)
	)
	(wire
		(pts
			(xy 100.33 231.14) (xy 107.95 231.14)
		)
		(stroke
			(width 0)
			(type default)
		)
	)
	(wire
		(pts
			(xy 138.43 204.47) (xy 138.43 205.74)
		)
		(stroke
			(width 0)
			(type default)
		)
	)
	(wire
		(pts
			(xy 199.39 143.51) (xy 207.01 143.51)
		)
		(stroke
			(width 0)
			(type default)
		)
	)
	(wire
		(pts
			(xy 240.03 194.31) (xy 237.49 194.31)
		)
		(stroke
			(width 0)
			(type default)
		)
	)
	(wire
		(pts
			(xy 123.19 213.36) (xy 115.57 213.36)
		)
		(stroke
			(width 0)
			(type default)
		)
	)
	(wire
		(pts
			(xy 184.15 153.67) (xy 191.77 153.67)
		)
		(stroke
			(width 0)
			(type default)
		)
	)
	(wire
		(pts
			(xy 187.96 31.75) (xy 187.96 29.21)
		)
		(stroke
			(width 0)
			(type default)
		)
	)
	(wire
		(pts
			(xy 207.01 153.67) (xy 199.39 153.67)
		)
		(stroke
			(width 0)
			(type default)
		)
	)
	(wire
		(pts
			(xy 157.48 86.36) (xy 165.1 86.36)
		)
		(stroke
			(width 0)
			(type default)
		)
	)
	(wire
		(pts
			(xy 149.86 86.36) (xy 149.86 88.9)
		)
		(stroke
			(width 0)
			(type default)
		)
	)
	(wire
		(pts
			(xy 214.63 231.14) (xy 214.63 233.68)
		)
		(stroke
			(width 0)
			(type default)
		)
	)
	(wire
		(pts
			(xy 161.29 241.3) (xy 153.67 241.3)
		)
		(stroke
			(width 0)
			(type default)
		)
	)
	(wire
		(pts
			(xy 165.1 86.36) (xy 172.72 86.36)
		)
		(stroke
			(width 0)
			(type default)
		)
	)
	(wire
		(pts
			(xy 184.15 213.36) (xy 191.77 213.36)
		)
		(stroke
			(width 0)
			(type default)
		)
	)
	(wire
		(pts
			(xy 191.77 231.14) (xy 191.77 233.68)
		)
		(stroke
			(width 0)
			(type default)
		)
	)
	(wire
		(pts
			(xy 130.81 241.3) (xy 138.43 241.3)
		)
		(stroke
			(width 0)
			(type default)
		)
	)
	(wire
		(pts
			(xy 237.49 213.36) (xy 237.49 215.9)
		)
		(stroke
			(width 0)
			(type default)
		)
	)
	(wire
		(pts
			(xy 229.87 177.8) (xy 229.87 179.07)
		)
		(stroke
			(width 0)
			(type default)
		)
	)
	(wire
		(pts
			(xy 165.1 36.83) (xy 165.1 39.37)
		)
		(stroke
			(width 0)
			(type default)
		)
	)
	(wire
		(pts
			(xy 368.3 243.84) (xy 369.57 243.84)
		)
		(stroke
			(width 0)
			(type default)
		)
	)
	(wire
		(pts
			(xy 214.63 213.36) (xy 214.63 215.9)
		)
		(stroke
			(width 0)
			(type default)
		)
	)
	(wire
		(pts
			(xy 245.11 213.36) (xy 245.11 231.14)
		)
		(stroke
			(width 0)
			(type default)
		)
	)
	(wire
		(pts
			(xy 229.87 143.51) (xy 237.49 143.51)
		)
		(stroke
			(width 0)
			(type default)
		)
	)
	(wire
		(pts
			(xy 369.57 246.38) (xy 360.68 246.38)
		)
		(stroke
			(width 0)
			(type default)
		)
	)
	(wire
		(pts
			(xy 207.01 223.52) (xy 207.01 220.98)
		)
		(stroke
			(width 0)
			(type default)
		)
	)
	(wire
		(pts
			(xy 229.87 185.42) (xy 229.87 186.69)
		)
		(stroke
			(width 0)
			(type default)
		)
	)
	(wire
		(pts
			(xy 153.67 223.52) (xy 153.67 220.98)
		)
		(stroke
			(width 0)
			(type default)
		)
	)
	(wire
		(pts
			(xy 153.67 194.31) (xy 153.67 196.85)
		)
		(stroke
			(width 0)
			(type default)
		)
	)
	(wire
		(pts
			(xy 222.25 143.51) (xy 229.87 143.51)
		)
		(stroke
			(width 0)
			(type default)
		)
	)
	(wire
		(pts
			(xy 199.39 151.13) (xy 199.39 153.67)
		)
		(stroke
			(width 0)
			(type default)
		)
	)
	(wire
		(pts
			(xy 138.43 201.93) (xy 138.43 204.47)
		)
		(stroke
			(width 0)
			(type default)
		)
	)
	(wire
		(pts
			(xy 139.7 29.21) (xy 149.86 29.21)
		)
		(stroke
			(width 0)
			(type default)
		)
	)
	(wire
		(pts
			(xy 146.05 204.47) (xy 146.05 201.93)
		)
		(stroke
			(width 0)
			(type default)
		)
	)
	(wire
		(pts
			(xy 157.48 39.37) (xy 165.1 39.37)
		)
		(stroke
			(width 0)
			(type default)
		)
	)
	(wire
		(pts
			(xy 226.06 78.74) (xy 226.06 76.2)
		)
		(stroke
			(width 0)
			(type default)
		)
	)
	(wire
		(pts
			(xy 207.01 241.3) (xy 207.01 238.76)
		)
		(stroke
			(width 0)
			(type default)
		)
	)
	(wire
		(pts
			(xy 229.87 213.36) (xy 229.87 215.9)
		)
		(stroke
			(width 0)
			(type default)
		)
	)
	(wire
		(pts
			(xy 191.77 146.05) (xy 191.77 143.51)
		)
		(stroke
			(width 0)
			(type default)
		)
	)
	(wire
		(pts
			(xy 229.87 66.04) (xy 237.49 66.04)
		)
		(stroke
			(width 0)
			(type default)
		)
	)
	(wire
		(pts
			(xy 229.87 213.36) (xy 237.49 213.36)
		)
		(stroke
			(width 0)
			(type default)
		)
	)
	(wire
		(pts
			(xy 203.2 78.74) (xy 210.82 78.74)
		)
		(stroke
			(width 0)
			(type default)
		)
	)
	(wire
		(pts
			(xy 176.53 194.31) (xy 184.15 194.31)
		)
		(stroke
			(width 0)
			(type default)
		)
	)
	(wire
		(pts
			(xy 161.29 213.36) (xy 161.29 215.9)
		)
		(stroke
			(width 0)
			(type default)
		)
	)
	(wire
		(pts
			(xy 168.91 231.14) (xy 176.53 231.14)
		)
		(stroke
			(width 0)
			(type default)
		)
	)
	(wire
		(pts
			(xy 168.91 223.52) (xy 176.53 223.52)
		)
		(stroke
			(width 0)
			(type default)
		)
	)
	(wire
		(pts
			(xy 157.48 96.52) (xy 165.1 96.52)
		)
		(stroke
			(width 0)
			(type default)
		)
	)
	(wire
		(pts
			(xy 157.48 93.98) (xy 157.48 96.52)
		)
		(stroke
			(width 0)
			(type default)
		)
	)
	(wire
		(pts
			(xy 229.87 153.67) (xy 222.25 153.67)
		)
		(stroke
			(width 0)
			(type default)
		)
	)
	(wire
		(pts
			(xy 207.01 204.47) (xy 214.63 204.47)
		)
		(stroke
			(width 0)
			(type default)
		)
	)
	(wire
		(pts
			(xy 379.73 224.79) (xy 383.54 224.79)
		)
		(stroke
			(width 0)
			(type default)
		)
	)
	(wire
		(pts
			(xy 222.25 220.98) (xy 222.25 223.52)
		)
		(stroke
			(width 0)
			(type default)
		)
	)
	(wire
		(pts
			(xy 367.03 219.71) (xy 367.03 222.25)
		)
		(stroke
			(width 0)
			(type default)
		)
	)
	(wire
		(pts
			(xy 397.51 242.57) (xy 397.51 250.19)
		)
		(stroke
			(width 0)
			(type default)
		)
	)
	(wire
		(pts
			(xy 123.19 231.14) (xy 123.19 233.68)
		)
		(stroke
			(width 0)
			(type default)
		)
	)
	(wire
		(pts
			(xy 199.39 215.9) (xy 199.39 213.36)
		)
		(stroke
			(width 0)
			(type default)
		)
	)
	(wire
		(pts
			(xy 210.82 29.21) (xy 218.44 29.21)
		)
		(stroke
			(width 0)
			(type default)
		)
	)
	(wire
		(pts
			(xy 184.15 194.31) (xy 191.77 194.31)
		)
		(stroke
			(width 0)
			(type default)
		)
	)
	(wire
		(pts
			(xy 172.72 29.21) (xy 180.34 29.21)
		)
		(stroke
			(width 0)
			(type default)
		)
	)
	(wire
		(pts
			(xy 227.33 55.88) (xy 227.33 53.34)
		)
		(stroke
			(width 0)
			(type default)
		)
	)
	(wire
		(pts
			(xy 381 222.25) (xy 379.73 222.25)
		)
		(stroke
			(width 0)
			(type default)
		)
	)
	(wire
		(pts
			(xy 139.7 86.36) (xy 149.86 86.36)
		)
		(stroke
			(width 0)
			(type default)
		)
	)
	(wire
		(pts
			(xy 107.95 231.14) (xy 107.95 233.68)
		)
		(stroke
			(width 0)
			(type default)
		)
	)
	(wire
		(pts
			(xy 187.96 68.58) (xy 187.96 71.12)
		)
		(stroke
			(width 0)
			(type default)
		)
	)
	(wire
		(pts
			(xy 191.77 153.67) (xy 199.39 153.67)
		)
		(stroke
			(width 0)
			(type default)
		)
	)
	(wire
		(pts
			(xy 218.44 68.58) (xy 218.44 71.12)
		)
		(stroke
			(width 0)
			(type default)
		)
	)
	(wire
		(pts
			(xy 248.92 193.04) (xy 250.19 193.04)
		)
		(stroke
			(width 0)
			(type default)
		)
	)
	(wire
		(pts
			(xy 180.34 68.58) (xy 187.96 68.58)
		)
		(stroke
			(width 0)
			(type default)
		)
	)
	(wire
		(pts
			(xy 168.91 213.36) (xy 168.91 215.9)
		)
		(stroke
			(width 0)
			(type default)
		)
	)
	(wire
		(pts
			(xy 250.19 181.61) (xy 240.03 181.61)
		)
		(stroke
			(width 0)
			(type default)
		)
	)
	(wire
		(pts
			(xy 184.15 223.52) (xy 184.15 220.98)
		)
		(stroke
			(width 0)
			(type default)
		)
	)
	(wire
		(pts
			(xy 165.1 39.37) (xy 172.72 39.37)
		)
		(stroke
			(width 0)
			(type default)
		)
	)
	(wire
		(pts
			(xy 184.15 153.67) (xy 184.15 154.94)
		)
		(stroke
			(width 0)
			(type default)
		)
	)
	(wire
		(pts
			(xy 233.68 55.88) (xy 227.33 55.88)
		)
		(stroke
			(width 0)
			(type default)
		)
	)
	(wire
		(pts
			(xy 381 246.38) (xy 379.73 246.38)
		)
		(stroke
			(width 0)
			(type default)
		)
	)
	(wire
		(pts
			(xy 191.77 223.52) (xy 199.39 223.52)
		)
		(stroke
			(width 0)
			(type default)
		)
	)
	(wire
		(pts
			(xy 214.63 163.83) (xy 214.63 161.29)
		)
		(stroke
			(width 0)
			(type default)
		)
	)
	(wire
		(pts
			(xy 180.34 78.74) (xy 180.34 76.2)
		)
		(stroke
			(width 0)
			(type default)
		)
	)
	(wire
		(pts
			(xy 149.86 86.36) (xy 157.48 86.36)
		)
		(stroke
			(width 0)
			(type default)
		)
	)
	(wire
		(pts
			(xy 199.39 194.31) (xy 199.39 196.85)
		)
		(stroke
			(width 0)
			(type default)
		)
	)
	(wire
		(pts
			(xy 250.19 190.5) (xy 248.92 190.5)
		)
		(stroke
			(width 0)
			(type default)
		)
	)
	(wire
		(pts
			(xy 229.87 153.67) (xy 237.49 153.67)
		)
		(stroke
			(width 0)
			(type default)
		)
	)
	(wire
		(pts
			(xy 207.01 194.31) (xy 207.01 196.85)
		)
		(stroke
			(width 0)
			(type default)
		)
	)
	(wire
		(pts
			(xy 130.81 223.52) (xy 138.43 223.52)
		)
		(stroke
			(width 0)
			(type default)
		)
	)
	(wire
		(pts
			(xy 237.49 161.29) (xy 245.11 161.29)
		)
		(stroke
			(width 0)
			(type default)
		)
	)
	(wire
		(pts
			(xy 226.06 96.52) (xy 233.68 96.52)
		)
		(stroke
			(width 0)
			(type default)
		)
	)
	(wire
		(pts
			(xy 161.29 213.36) (xy 168.91 213.36)
		)
		(stroke
			(width 0)
			(type default)
		)
	)
	(wire
		(pts
			(xy 146.05 194.31) (xy 153.67 194.31)
		)
		(stroke
			(width 0)
			(type default)
		)
	)
	(wire
		(pts
			(xy 195.58 78.74) (xy 203.2 78.74)
		)
		(stroke
			(width 0)
			(type default)
		)
	)
	(wire
		(pts
			(xy 149.86 78.74) (xy 149.86 80.01)
		)
		(stroke
			(width 0)
			(type default)
		)
	)
	(wire
		(pts
			(xy 233.68 39.37) (xy 226.06 39.37)
		)
		(stroke
			(width 0)
			(type default)
		)
	)
	(wire
		(pts
			(xy 195.58 29.21) (xy 203.2 29.21)
		)
		(stroke
			(width 0)
			(type default)
		)
	)
	(wire
		(pts
			(xy 100.33 241.3) (xy 100.33 238.76)
		)
		(stroke
			(width 0)
			(type default)
		)
	)
	(wire
		(pts
			(xy 214.63 171.45) (xy 214.63 168.91)
		)
		(stroke
			(width 0)
			(type default)
		)
	)
	(wire
		(pts
			(xy 195.58 39.37) (xy 195.58 36.83)
		)
		(stroke
			(width 0)
			(type default)
		)
	)
	(wire
		(pts
			(xy 203.2 96.52) (xy 203.2 93.98)
		)
		(stroke
			(width 0)
			(type default)
		)
	)
	(wire
		(pts
			(xy 168.91 231.14) (xy 168.91 233.68)
		)
		(stroke
			(width 0)
			(type default)
		)
	)
	(wire
		(pts
			(xy 184.15 213.36) (xy 184.15 215.9)
		)
		(stroke
			(width 0)
			(type default)
		)
	)
	(wire
		(pts
			(xy 381 241.3) (xy 379.73 241.3)
		)
		(stroke
			(width 0)
			(type default)
		)
	)
	(wire
		(pts
			(xy 123.19 213.36) (xy 123.19 215.9)
		)
		(stroke
			(width 0)
			(type default)
		)
	)
	(wire
		(pts
			(xy 187.96 86.36) (xy 195.58 86.36)
		)
		(stroke
			(width 0)
			(type default)
		)
	)
	(wire
		(pts
			(xy 191.77 204.47) (xy 191.77 201.93)
		)
		(stroke
			(width 0)
			(type default)
		)
	)
	(wire
		(pts
			(xy 222.25 194.31) (xy 222.25 196.85)
		)
		(stroke
			(width 0)
			(type default)
		)
	)
	(wire
		(pts
			(xy 138.43 213.36) (xy 138.43 215.9)
		)
		(stroke
			(width 0)
			(type default)
		)
	)
	(wire
		(pts
			(xy 233.68 68.58) (xy 233.68 86.36)
		)
		(stroke
			(width 0)
			(type default)
		)
	)
	(wire
		(pts
			(xy 229.87 143.51) (xy 229.87 146.05)
		)
		(stroke
			(width 0)
			(type default)
		)
	)
	(wire
		(pts
			(xy 191.77 231.14) (xy 199.39 231.14)
		)
		(stroke
			(width 0)
			(type default)
		)
	)
	(wire
		(pts
			(xy 165.1 86.36) (xy 165.1 88.9)
		)
		(stroke
			(width 0)
			(type default)
		)
	)
	(wire
		(pts
			(xy 180.34 78.74) (xy 187.96 78.74)
		)
		(stroke
			(width 0)
			(type default)
		)
	)
	(wire
		(pts
			(xy 207.01 213.36) (xy 207.01 215.9)
		)
		(stroke
			(width 0)
			(type default)
		)
	)
	(wire
		(pts
			(xy 222.25 161.29) (xy 229.87 161.29)
		)
		(stroke
			(width 0)
			(type default)
		)
	)
	(wire
		(pts
			(xy 172.72 86.36) (xy 172.72 88.9)
		)
		(stroke
			(width 0)
			(type default)
		)
	)
	(wire
		(pts
			(xy 229.87 204.47) (xy 237.49 204.47)
		)
		(stroke
			(width 0)
			(type default)
		)
	)
	(wire
		(pts
			(xy 107.95 231.14) (xy 115.57 231.14)
		)
		(stroke
			(width 0)
			(type default)
		)
	)
	(wire
		(pts
			(xy 237.49 64.77) (xy 237.49 66.04)
		)
		(stroke
			(width 0)
			(type default)
		)
	)
	(wire
		(pts
			(xy 219.71 45.72) (xy 219.71 48.26)
		)
		(stroke
			(width 0)
			(type default)
		)
	)
	(wire
		(pts
			(xy 168.91 204.47) (xy 176.53 204.47)
		)
		(stroke
			(width 0)
			(type default)
		)
	)
	(wire
		(pts
			(xy 149.86 29.21) (xy 149.86 31.75)
		)
		(stroke
			(width 0)
			(type default)
		)
	)
	(wire
		(pts
			(xy 250.19 176.53) (xy 245.11 176.53)
		)
		(stroke
			(width 0)
			(type default)
		)
	)
	(wire
		(pts
			(xy 229.87 153.67) (xy 229.87 151.13)
		)
		(stroke
			(width 0)
			(type default)
		)
	)
	(wire
		(pts
			(xy 229.87 231.14) (xy 229.87 233.68)
		)
		(stroke
			(width 0)
			(type default)
		)
	)
	(wire
		(pts
			(xy 180.34 29.21) (xy 187.96 29.21)
		)
		(stroke
			(width 0)
			(type default)
		)
	)
	(wire
		(pts
			(xy 149.86 78.74) (xy 157.48 78.74)
		)
		(stroke
			(width 0)
			(type default)
		)
	)
	(wire
		(pts
			(xy 149.86 96.52) (xy 149.86 97.79)
		)
		(stroke
			(width 0)
			(type default)
		)
	)
	(wire
		(pts
			(xy 107.95 241.3) (xy 107.95 238.76)
		)
		(stroke
			(width 0)
			(type default)
		)
	)
	(wire
		(pts
			(xy 161.29 231.14) (xy 168.91 231.14)
		)
		(stroke
			(width 0)
			(type default)
		)
	)
	(wire
		(pts
			(xy 191.77 241.3) (xy 184.15 241.3)
		)
		(stroke
			(width 0)
			(type default)
		)
	)
	(wire
		(pts
			(xy 233.68 45.72) (xy 227.33 45.72)
		)
		(stroke
			(width 0)
			(type default)
		)
	)
	(wire
		(pts
			(xy 176.53 213.36) (xy 184.15 213.36)
		)
		(stroke
			(width 0)
			(type default)
		)
	)
	(wire
		(pts
			(xy 157.48 29.21) (xy 165.1 29.21)
		)
		(stroke
			(width 0)
			(type default)
		)
	)
	(wire
		(pts
			(xy 218.44 86.36) (xy 218.44 88.9)
		)
		(stroke
			(width 0)
			(type default)
		)
	)
	(wire
		(pts
			(xy 233.68 53.34) (xy 233.68 55.88)
		)
		(stroke
			(width 0)
			(type default)
		)
	)
	(wire
		(pts
			(xy 222.25 215.9) (xy 222.25 213.36)
		)
		(stroke
			(width 0)
			(type default)
		)
	)
	(wire
		(pts
			(xy 115.57 213.36) (xy 115.57 231.14)
		)
		(stroke
			(width 0)
			(type default)
		)
	)
	(wire
		(pts
			(xy 180.34 29.21) (xy 180.34 31.75)
		)
		(stroke
			(width 0)
			(type default)
		)
	)
	(wire
		(pts
			(xy 168.91 241.3) (xy 161.29 241.3)
		)
		(stroke
			(width 0)
			(type default)
		)
	)
	(wire
		(pts
			(xy 180.34 36.83) (xy 180.34 39.37)
		)
		(stroke
			(width 0)
			(type default)
		)
	)
	(wire
		(pts
			(xy 168.91 213.36) (xy 176.53 213.36)
		)
		(stroke
			(width 0)
			(type default)
		)
	)
	(wire
		(pts
			(xy 222.25 171.45) (xy 222.25 168.91)
		)
		(stroke
			(width 0)
			(type default)
		)
	)
	(wire
		(pts
			(xy 146.05 213.36) (xy 146.05 215.9)
		)
		(stroke
			(width 0)
			(type default)
		)
	)
	(wire
		(pts
			(xy 214.63 223.52) (xy 222.25 223.52)
		)
		(stroke
			(width 0)
			(type default)
		)
	)
	(wire
		(pts
			(xy 123.19 223.52) (xy 123.19 220.98)
		)
		(stroke
			(width 0)
			(type default)
		)
	)
	(wire
		(pts
			(xy 219.71 55.88) (xy 219.71 57.15)
		)
		(stroke
			(width 0)
			(type default)
		)
	)
	(wire
		(pts
			(xy 138.43 223.52) (xy 146.05 223.52)
		)
		(stroke
			(width 0)
			(type default)
		)
	)
	(wire
		(pts
			(xy 203.2 96.52) (xy 210.82 96.52)
		)
		(stroke
			(width 0)
			(type default)
		)
	)
	(wire
		(pts
			(xy 195.58 68.58) (xy 203.2 68.58)
		)
		(stroke
			(width 0)
			(type default)
		)
	)
	(wire
		(pts
			(xy 157.48 68.58) (xy 165.1 68.58)
		)
		(stroke
			(width 0)
			(type default)
		)
	)
	(wire
		(pts
			(xy 176.53 231.14) (xy 184.15 231.14)
		)
		(stroke
			(width 0)
			(type default)
		)
	)
	(wire
		(pts
			(xy 180.34 86.36) (xy 180.34 88.9)
		)
		(stroke
			(width 0)
			(type default)
		)
	)
	(wire
		(pts
			(xy 139.7 27.94) (xy 139.7 29.21)
		)
		(stroke
			(width 0)
			(type default)
		)
	)
	(wire
		(pts
			(xy 210.82 68.58) (xy 218.44 68.58)
		)
		(stroke
			(width 0)
			(type default)
		)
	)
	(wire
		(pts
			(xy 237.49 153.67) (xy 237.49 151.13)
		)
		(stroke
			(width 0)
			(type default)
		)
	)
	(wire
		(pts
			(xy 229.87 171.45) (xy 222.25 171.45)
		)
		(stroke
			(width 0)
			(type default)
		)
	)
	(wire
		(pts
			(xy 153.67 213.36) (xy 153.67 215.9)
		)
		(stroke
			(width 0)
			(type default)
		)
	)
	(wire
		(pts
			(xy 138.43 213.36) (xy 146.05 213.36)
		)
		(stroke
			(width 0)
			(type default)
		)
	)
	(wire
		(pts
			(xy 191.77 204.47) (xy 199.39 204.47)
		)
		(stroke
			(width 0)
			(type default)
		)
	)
	(wire
		(pts
			(xy 168.91 204.47) (xy 168.91 201.93)
		)
		(stroke
			(width 0)
			(type default)
		)
	)
	(wire
		(pts
			(xy 210.82 39.37) (xy 210.82 36.83)
		)
		(stroke
			(width 0)
			(type default)
		)
	)
	(wire
		(pts
			(xy 229.87 168.91) (xy 229.87 171.45)
		)
		(stroke
			(width 0)
			(type default)
		)
	)
	(wire
		(pts
			(xy 222.25 238.76) (xy 222.25 241.3)
		)
		(stroke
			(width 0)
			(type default)
		)
	)
	(wire
		(pts
			(xy 214.63 196.85) (xy 214.63 194.31)
		)
		(stroke
			(width 0)
			(type default)
		)
	)
	(wire
		(pts
			(xy 149.86 96.52) (xy 157.48 96.52)
		)
		(stroke
			(width 0)
			(type default)
		)
	)
	(wire
		(pts
			(xy 210.82 68.58) (xy 210.82 71.12)
		)
		(stroke
			(width 0)
			(type default)
		)
	)
	(wire
		(pts
			(xy 383.54 243.84) (xy 383.54 238.76)
		)
		(stroke
			(width 0)
			(type default)
		)
	)
	(wire
		(pts
			(xy 218.44 68.58) (xy 226.06 68.58)
		)
		(stroke
			(width 0)
			(type default)
		)
	)
	(wire
		(pts
			(xy 379.73 243.84) (xy 383.54 243.84)
		)
		(stroke
			(width 0)
			(type default)
		)
	)
	(wire
		(pts
			(xy 191.77 213.36) (xy 199.39 213.36)
		)
		(stroke
			(width 0)
			(type default)
		)
	)
	(wire
		(pts
			(xy 139.7 67.31) (xy 139.7 68.58)
		)
		(stroke
			(width 0)
			(type default)
		)
	)
	(wire
		(pts
			(xy 184.15 241.3) (xy 176.53 241.3)
		)
		(stroke
			(width 0)
			(type default)
		)
	)
	(wire
		(pts
			(xy 199.39 204.47) (xy 207.01 204.47)
		)
		(stroke
			(width 0)
			(type default)
		)
	)
	(wire
		(pts
			(xy 123.19 241.3) (xy 130.81 241.3)
		)
		(stroke
			(width 0)
			(type default)
		)
	)
	(wire
		(pts
			(xy 203.2 86.36) (xy 210.82 86.36)
		)
		(stroke
			(width 0)
			(type default)
		)
	)
	(wire
		(pts
			(xy 191.77 153.67) (xy 191.77 151.13)
		)
		(stroke
			(width 0)
			(type default)
		)
	)
	(wire
		(pts
			(xy 245.11 176.53) (xy 245.11 161.29)
		)
		(stroke
			(width 0)
			(type default)
		)
	)
	(wire
		(pts
			(xy 168.91 241.3) (xy 168.91 238.76)
		)
		(stroke
			(width 0)
			(type default)
		)
	)
	(wire
		(pts
			(xy 203.2 78.74) (xy 203.2 76.2)
		)
		(stroke
			(width 0)
			(type default)
		)
	)
	(wire
		(pts
			(xy 227.33 55.88) (xy 219.71 55.88)
		)
		(stroke
			(width 0)
			(type default)
		)
	)
	(wire
		(pts
			(xy 233.68 48.26) (xy 233.68 45.72)
		)
		(stroke
			(width 0)
			(type default)
		)
	)
	(wire
		(pts
			(xy 172.72 96.52) (xy 172.72 93.98)
		)
		(stroke
			(width 0)
			(type default)
		)
	)
	(wire
		(pts
			(xy 226.06 36.83) (xy 226.06 39.37)
		)
		(stroke
			(width 0)
			(type default)
		)
	)
	(wire
		(pts
			(xy 187.96 88.9) (xy 187.96 86.36)
		)
		(stroke
			(width 0)
			(type default)
		)
	)
	(wire
		(pts
			(xy 172.72 68.58) (xy 180.34 68.58)
		)
		(stroke
			(width 0)
			(type default)
		)
	)
	(wire
		(pts
			(xy 210.82 39.37) (xy 218.44 39.37)
		)
		(stroke
			(width 0)
			(type default)
		)
	)
	(wire
		(pts
			(xy 214.63 213.36) (xy 222.25 213.36)
		)
		(stroke
			(width 0)
			(type default)
		)
	)
	(wire
		(pts
			(xy 222.25 194.31) (xy 229.87 194.31)
		)
		(stroke
			(width 0)
			(type default)
		)
	)
	(wire
		(pts
			(xy 237.49 143.51) (xy 250.19 143.51)
		)
		(stroke
			(width 0)
			(type default)
		)
	)
	(wire
		(pts
			(xy 100.33 241.3) (xy 100.33 242.57)
		)
		(stroke
			(width 0)
			(type default)
		)
	)
	(wire
		(pts
			(xy 199.39 220.98) (xy 199.39 223.52)
		)
		(stroke
			(width 0)
			(type default)
		)
	)
	(wire
		(pts
			(xy 214.63 194.31) (xy 222.25 194.31)
		)
		(stroke
			(width 0)
			(type default)
		)
	)
	(wire
		(pts
			(xy 237.49 146.05) (xy 237.49 143.51)
		)
		(stroke
			(width 0)
			(type default)
		)
	)
	(wire
		(pts
			(xy 146.05 241.3) (xy 138.43 241.3)
		)
		(stroke
			(width 0)
			(type default)
		)
	)
	(wire
		(pts
			(xy 368.3 250.19) (xy 368.3 243.84)
		)
		(stroke
			(width 0)
			(type default)
		)
	)
	(wire
		(pts
			(xy 248.92 62.23) (xy 245.11 62.23)
		)
		(stroke
			(width 0)
			(type default)
		)
	)
	(wire
		(pts
			(xy 226.06 29.21) (xy 233.68 29.21)
		)
		(stroke
			(width 0)
			(type default)
		)
	)
	(wire
		(pts
			(xy 180.34 39.37) (xy 187.96 39.37)
		)
		(stroke
			(width 0)
			(type default)
		)
	)
	(wire
		(pts
			(xy 207.01 143.51) (xy 214.63 143.51)
		)
		(stroke
			(width 0)
			(type default)
		)
	)
	(wire
		(pts
			(xy 172.72 68.58) (xy 172.72 71.12)
		)
		(stroke
			(width 0)
			(type default)
		)
	)
	(wire
		(pts
			(xy 219.71 55.88) (xy 219.71 53.34)
		)
		(stroke
			(width 0)
			(type default)
		)
	)
	(wire
		(pts
			(xy 157.48 39.37) (xy 149.86 39.37)
		)
		(stroke
			(width 0)
			(type default)
		)
	)
	(wire
		(pts
			(xy 195.58 86.36) (xy 195.58 88.9)
		)
		(stroke
			(width 0)
			(type default)
		)
	)
	(wire
		(pts
			(xy 199.39 194.31) (xy 207.01 194.31)
		)
		(stroke
			(width 0)
			(type default)
		)
	)
	(wire
		(pts
			(xy 199.39 233.68) (xy 199.39 231.14)
		)
		(stroke
			(width 0)
			(type default)
		)
	)
	(wire
		(pts
			(xy 161.29 204.47) (xy 153.67 204.47)
		)
		(stroke
			(width 0)
			(type default)
		)
	)
	(wire
		(pts
			(xy 184.15 151.13) (xy 184.15 153.67)
		)
		(stroke
			(width 0)
			(type default)
		)
	)
	(wire
		(pts
			(xy 229.87 223.52) (xy 237.49 223.52)
		)
		(stroke
			(width 0)
			(type default)
		)
	)
	(wire
		(pts
			(xy 222.25 153.67) (xy 214.63 153.67)
		)
		(stroke
			(width 0)
			(type default)
		)
	)
	(wire
		(pts
			(xy 229.87 204.47) (xy 229.87 201.93)
		)
		(stroke
			(width 0)
			(type default)
		)
	)
	(wire
		(pts
			(xy 381 246.38) (xy 381 250.19)
		)
		(stroke
			(width 0)
			(type default)
		)
	)
	(wire
		(pts
			(xy 130.81 223.52) (xy 123.19 223.52)
		)
		(stroke
			(width 0)
			(type default)
		)
	)
	(wire
		(pts
			(xy 130.81 231.14) (xy 130.81 233.68)
		)
		(stroke
			(width 0)
			(type default)
		)
	)
	(wire
		(pts
			(xy 161.29 194.31) (xy 161.29 196.85)
		)
		(stroke
			(width 0)
			(type default)
		)
	)
	(wire
		(pts
			(xy 153.67 241.3) (xy 153.67 238.76)
		)
		(stroke
			(width 0)
			(type default)
		)
	)
	(wire
		(pts
			(xy 210.82 96.52) (xy 218.44 96.52)
		)
		(stroke
			(width 0)
			(type default)
		)
	)
	(wire
		(pts
			(xy 207.01 153.67) (xy 207.01 151.13)
		)
		(stroke
			(width 0)
			(type default)
		)
	)
	(wire
		(pts
			(xy 149.86 96.52) (xy 149.86 93.98)
		)
		(stroke
			(width 0)
			(type default)
		)
	)
	(wire
		(pts
			(xy 157.48 88.9) (xy 157.48 86.36)
		)
		(stroke
			(width 0)
			(type default)
		)
	)
	(wire
		(pts
			(xy 146.05 204.47) (xy 153.67 204.47)
		)
		(stroke
			(width 0)
			(type default)
		)
	)
	(wire
		(pts
			(xy 222.25 151.13) (xy 222.25 153.67)
		)
		(stroke
			(width 0)
			(type default)
		)
	)
	(wire
		(pts
			(xy 172.72 36.83) (xy 172.72 39.37)
		)
		(stroke
			(width 0)
			(type default)
		)
	)
	(wire
		(pts
			(xy 381 222.25) (xy 381 227.33)
		)
		(stroke
			(width 0)
			(type default)
		)
	)
	(wire
		(pts
			(xy 207.01 143.51) (xy 207.01 146.05)
		)
		(stroke
			(width 0)
			(type default)
		)
	)
	(wire
		(pts
			(xy 149.86 29.21) (xy 157.48 29.21)
		)
		(stroke
			(width 0)
			(type default)
		)
	)
	(wire
		(pts
			(xy 184.15 143.51) (xy 191.77 143.51)
		)
		(stroke
			(width 0)
			(type default)
		)
	)
	(wire
		(pts
			(xy 130.81 223.52) (xy 130.81 220.98)
		)
		(stroke
			(width 0)
			(type default)
		)
	)
	(wire
		(pts
			(xy 191.77 143.51) (xy 199.39 143.51)
		)
		(stroke
			(width 0)
			(type default)
		)
	)
	(wire
		(pts
			(xy 107.95 241.3) (xy 115.57 241.3)
		)
		(stroke
			(width 0)
			(type default)
		)
	)
	(wire
		(pts
			(xy 146.05 231.14) (xy 146.05 233.68)
		)
		(stroke
			(width 0)
			(type default)
		)
	)
	(wire
		(pts
			(xy 161.29 201.93) (xy 161.29 204.47)
		)
		(stroke
			(width 0)
			(type default)
		)
	)
	(wire
		(pts
			(xy 207.01 231.14) (xy 214.63 231.14)
		)
		(stroke
			(width 0)
			(type default)
		)
	)
	(wire
		(pts
			(xy 207.01 231.14) (xy 207.01 233.68)
		)
		(stroke
			(width 0)
			(type default)
		)
	)
	(wire
		(pts
			(xy 210.82 86.36) (xy 218.44 86.36)
		)
		(stroke
			(width 0)
			(type default)
		)
	)
	(wire
		(pts
			(xy 237.49 194.31) (xy 229.87 194.31)
		)
		(stroke
			(width 0)
			(type default)
		)
	)
	(wire
		(pts
			(xy 199.39 241.3) (xy 207.01 241.3)
		)
		(stroke
			(width 0)
			(type default)
		)
	)
	(wire
		(pts
			(xy 219.71 44.45) (xy 219.71 45.72)
		)
		(stroke
			(width 0)
			(type default)
		)
	)
	(wire
		(pts
			(xy 146.05 231.14) (xy 153.67 231.14)
		)
		(stroke
			(width 0)
			(type default)
		)
	)
	(wire
		(pts
			(xy 369.57 227.33) (xy 360.68 227.33)
		)
		(stroke
			(width 0)
			(type default)
		)
	)
	(wire
		(pts
			(xy 210.82 96.52) (xy 210.82 93.98)
		)
		(stroke
			(width 0)
			(type default)
		)
	)
	(wire
		(pts
			(xy 237.49 231.14) (xy 237.49 233.68)
		)
		(stroke
			(width 0)
			(type default)
		)
	)
	(wire
		(pts
			(xy 180.34 86.36) (xy 187.96 86.36)
		)
		(stroke
			(width 0)
			(type default)
		)
	)
	(wire
		(pts
			(xy 138.43 193.04) (xy 138.43 194.31)
		)
		(stroke
			(width 0)
			(type default)
		)
	)
	(wire
		(pts
			(xy 157.48 78.74) (xy 157.48 76.2)
		)
		(stroke
			(width 0)
			(type default)
		)
	)
	(wire
		(pts
			(xy 240.03 71.12) (xy 248.92 71.12)
		)
		(stroke
			(width 0)
			(type default)
		)
	)
	(wire
		(pts
			(xy 165.1 78.74) (xy 172.72 78.74)
		)
		(stroke
			(width 0)
			(type default)
		)
	)
	(wire
		(pts
			(xy 146.05 194.31) (xy 146.05 196.85)
		)
		(stroke
			(width 0)
			(type default)
		)
	)
	(wire
		(pts
			(xy 245.11 62.23) (xy 245.11 45.72)
		)
		(stroke
			(width 0)
			(type default)
		)
	)
	(wire
		(pts
			(xy 149.86 68.58) (xy 157.48 68.58)
		)
		(stroke
			(width 0)
			(type default)
		)
	)
	(wire
		(pts
			(xy 214.63 223.52) (xy 214.63 220.98)
		)
		(stroke
			(width 0)
			(type default)
		)
	)
	(wire
		(pts
			(xy 168.91 204.47) (xy 161.29 204.47)
		)
		(stroke
			(width 0)
			(type default)
		)
	)
	(wire
		(pts
			(xy 381 227.33) (xy 379.73 227.33)
		)
		(stroke
			(width 0)
			(type default)
		)
	)
	(wire
		(pts
			(xy 184.15 231.14) (xy 184.15 233.68)
		)
		(stroke
			(width 0)
			(type default)
		)
	)
	(wire
		(pts
			(xy 168.91 241.3) (xy 176.53 241.3)
		)
		(stroke
			(width 0)
			(type default)
		)
	)
	(wire
		(pts
			(xy 360.68 246.38) (xy 360.68 243.84)
		)
		(stroke
			(width 0)
			(type default)
		)
	)
	(label "MGTRREF"
		(at 215.9 66.04 0)
		(effects
			(font
				(size 1.27 1.27)
			)
			(justify left bottom)
		)
	)
	(label "MGTRREF"
		(at 240.03 71.12 0)
		(effects
			(font
				(size 1.27 1.27)
			)
			(justify left bottom)
		)
	)
	(symbol
		(lib_id "antmicroCapacitorsmisc:C_100n_0201")
		(at 210.82 93.98 90)
		(unit 1)
		(exclude_from_sim no)
		(in_bom yes)
		(on_board yes)
		(dnp no)
		(property "Reference" "C153"
			(at 211.455 89.535 90)
			(effects
				(font
					(size 1.27 1.27)
				)
				(justify right)
			)
		)
		(property "Value" "C_100n_0201"
			(at 220.98 73.66 0)
			(effects
				(font
					(size 1.27 1.27)
					(thickness 0.15)
				)
				(justify left bottom)
				(hide yes)
			)
		)
		(property "Footprint" "antmicro-footprints:C_0201"
			(at 223.52 73.66 0)
			(effects
				(font
					(size 1.27 1.27)
					(thickness 0.15)
				)
				(justify left bottom)
				(hide yes)
			)
		)
		(property "Datasheet" "https://www.yageo.com/en/Chart/Download/pdf/CC0201KRX6S5BB104"
			(at 226.06 73.66 0)
			(effects
				(font
					(size 1.27 1.27)
					(thickness 0.15)
				)
				(justify left bottom)
				(hide yes)
			)
		)
		(property "Description" ""
			(at 210.82 93.98 0)
			(effects
				(font
					(size 1.27 1.27)
				)
			)
		)
		(property "Manufacturer" "YAGEO"
			(at 231.14 73.66 0)
			(effects
				(font
					(size 1.27 1.27)
					(thickness 0.15)
				)
				(justify left bottom)
				(hide yes)
			)
		)
		(property "MPN" "CC0201KRX6S5BB104"
			(at 228.6 73.66 0)
			(effects
				(font
					(size 1.27 1.27)
					(thickness 0.15)
				)
				(justify left bottom)
				(hide yes)
			)
		)
		(property "Val" "100n"
			(at 211.455 93.345 90)
			(effects
				(font
					(size 1.27 1.27)
					(thickness 0.15)
				)
				(justify right)
			)
		)
		(property "License" "Apache-2.0"
			(at 233.68 73.66 0)
			(effects
				(font
					(size 1.27 1.27)
					(thickness 0.15)
				)
				(justify left bottom)
				(hide yes)
			)
		)
		(property "Author" "Antmicro"
			(at 236.22 73.66 0)
			(effects
				(font
					(size 1.27 1.27)
					(thickness 0.15)
				)
				(justify left bottom)
				(hide yes)
			)
		)
		(property "Voltage" ""
			(at 238.76 73.66 0)
			(effects
				(font
					(size 1.27 1.27)
				)
				(justify left bottom)
				(hide yes)
			)
		)
		(property "Dielectric" ""
			(at 241.3 73.66 0)
			(effects
				(font
					(size 1.27 1.27)
				)
				(justify left bottom)
				(hide yes)
			)
		)
		(pin "1"
		)
		(pin "2"
		)
		(instances
			(project "k410t-devboard"
				(path ""
					(reference "C153")
					(unit 1)
				)
			)
		)
	)
	(symbol
		(lib_id "antmicroCapacitors0603:C_47u_0603")
		(at 184.15 151.13 90)
		(unit 1)
		(exclude_from_sim no)
		(in_bom yes)
		(on_board yes)
		(dnp no)
		(property "Reference" "C46"
			(at 184.785 146.685 90)
			(effects
				(font
					(size 1.27 1.27)
				)
				(justify right)
			)
		)
		(property "Value" "C_47u_0603"
			(at 194.31 130.81 0)
			(effects
				(font
					(size 1.27 1.27)
					(thickness 0.15)
				)
				(justify left bottom)
				(hide yes)
			)
		)
		(property "Footprint" "antmicro-footprints:C_0603_1608Metric"
			(at 196.85 130.81 0)
			(effects
				(font
					(size 1.27 1.27)
					(thickness 0.15)
				)
				(justify left bottom)
				(hide yes)
			)
		)
		(property "Datasheet" "https://www.murata.com/products/productdetail?partno=GRM188R60J476ME15%23"
			(at 199.39 130.81 0)
			(effects
				(font
					(size 1.27 1.27)
					(thickness 0.15)
				)
				(justify left bottom)
				(hide yes)
			)
		)
		(property "Description" ""
			(at 184.15 151.13 0)
			(effects
				(font
					(size 1.27 1.27)
				)
			)
		)
		(property "Manufacturer" "Murata"
			(at 204.47 130.81 0)
			(effects
				(font
					(size 1.27 1.27)
					(thickness 0.15)
				)
				(justify left bottom)
				(hide yes)
			)
		)
		(property "MPN" "GRM188R60J476ME15D"
			(at 201.93 130.81 0)
			(effects
				(font
					(size 1.27 1.27)
					(thickness 0.15)
				)
				(justify left bottom)
				(hide yes)
			)
		)
		(property "Val" "47u"
			(at 184.785 150.495 90)
			(effects
				(font
					(size 1.27 1.27)
					(thickness 0.15)
				)
				(justify right)
			)
		)
		(property "License" "Apache-2.0"
			(at 207.01 130.81 0)
			(effects
				(font
					(size 1.27 1.27)
					(thickness 0.15)
				)
				(justify left bottom)
				(hide yes)
			)
		)
		(property "Author" "Antmicro"
			(at 209.55 130.81 0)
			(effects
				(font
					(size 1.27 1.27)
					(thickness 0.15)
				)
				(justify left bottom)
				(hide yes)
			)
		)
		(property "Voltage" ""
			(at 212.09 130.81 0)
			(effects
				(font
					(size 1.27 1.27)
				)
				(justify left bottom)
				(hide yes)
			)
		)
		(property "Dielectric" ""
			(at 214.63 130.81 0)
			(effects
				(font
					(size 1.27 1.27)
				)
				(justify left bottom)
				(hide yes)
			)
		)
		(pin "1"
		)
		(pin "2"
		)
		(instances
			(project "k410t-devboard"
				(path ""
					(reference "C46")
					(unit 1)
				)
			)
		)
	)
	(symbol
		(lib_id "antmicropower:+1V0")
		(at 138.43 193.04 0)
		(mirror y)
		(unit 1)
		(exclude_from_sim no)
		(in_bom yes)
		(on_board yes)
		(dnp no)
		(fields_autoplaced yes)
		(property "Reference" "#PWR01"
			(at 138.43 196.85 0)
			(effects
				(font
					(size 1.27 1.27)
				)
				(hide yes)
			)
		)
		(property "Value" "+1V0"
			(at 138.43 189.484 0)
			(effects
				(font
					(size 1.27 1.27)
				)
			)
		)
		(property "Footprint" ""
			(at 138.43 193.04 0)
			(effects
				(font
					(size 1.27 1.27)
				)
				(hide yes)
			)
		)
		(property "Datasheet" ""
			(at 138.43 193.04 0)
			(effects
				(font
					(size 1.27 1.27)
				)
				(hide yes)
			)
		)
		(property "Description" ""
			(at 138.43 193.04 0)
			(effects
				(font
					(size 1.27 1.27)
				)
			)
		)
		(pin "1"
		)
		(instances
			(project "k410t-devboard"
				(path ""
					(reference "#PWR01")
					(unit 1)
				)
			)
		)
	)
	(symbol
		(lib_id "antmicroCapacitors0402:C_100n_0402")
		(at 172.72 93.98 90)
		(unit 1)
		(exclude_from_sim no)
		(in_bom yes)
		(on_board yes)
		(dnp no)
		(property "Reference" "C143"
			(at 173.355 89.535 90)
			(effects
				(font
					(size 1.27 1.27)
				)
				(justify right)
			)
		)
		(property "Value" "C_100n_0402"
			(at 182.88 73.66 0)
			(effects
				(font
					(size 1.27 1.27)
					(thickness 0.15)
				)
				(justify left bottom)
				(hide yes)
			)
		)
		(property "Footprint" "antmicro-footprints:C_0402_1005Metric"
			(at 185.42 73.66 0)
			(effects
				(font
					(size 1.27 1.27)
					(thickness 0.15)
				)
				(justify left bottom)
				(hide yes)
			)
		)
		(property "Datasheet" "https://www.murata.com/products/productdetail?partno=GRM155R61H104KE14%23"
			(at 187.96 73.66 0)
			(effects
				(font
					(size 1.27 1.27)
					(thickness 0.15)
				)
				(justify left bottom)
				(hide yes)
			)
		)
		(property "Description" ""
			(at 172.72 93.98 0)
			(effects
				(font
					(size 1.27 1.27)
				)
			)
		)
		(property "Manufacturer" "Murata"
			(at 193.04 73.66 0)
			(effects
				(font
					(size 1.27 1.27)
					(thickness 0.15)
				)
				(justify left bottom)
				(hide yes)
			)
		)
		(property "MPN" "GRM155R61H104KE14D"
			(at 190.5 73.66 0)
			(effects
				(font
					(size 1.27 1.27)
					(thickness 0.15)
				)
				(justify left bottom)
				(hide yes)
			)
		)
		(property "Val" "100n"
			(at 173.355 93.345 90)
			(effects
				(font
					(size 1.27 1.27)
					(thickness 0.15)
				)
				(justify right)
			)
		)
		(property "License" "Apache-2.0"
			(at 195.58 73.66 0)
			(effects
				(font
					(size 1.27 1.27)
					(thickness 0.15)
				)
				(justify left bottom)
				(hide yes)
			)
		)
		(property "Author" "Antmicro"
			(at 198.12 73.66 0)
			(effects
				(font
					(size 1.27 1.27)
					(thickness 0.15)
				)
				(justify left bottom)
				(hide yes)
			)
		)
		(property "Voltage" "50V"
			(at 200.66 73.66 0)
			(effects
				(font
					(size 1.27 1.27)
				)
				(justify left bottom)
				(hide yes)
			)
		)
		(property "Dielectric" "X5R"
			(at 203.2 73.66 0)
			(effects
				(font
					(size 1.27 1.27)
				)
				(justify left bottom)
				(hide yes)
			)
		)
		(pin "1"
		)
		(pin "2"
		)
		(instances
			(project "k410t-devboard"
				(path ""
					(reference "C143")
					(unit 1)
				)
			)
		)
	)
	(symbol
		(lib_id "antmicroCapacitors0402:C_100n_0402")
		(at 184.15 238.76 270)
		(mirror x)
		(unit 1)
		(exclude_from_sim no)
		(in_bom yes)
		(on_board yes)
		(dnp no)
		(property "Reference" "C136"
			(at 183.515 234.315 90)
			(effects
				(font
					(size 1.27 1.27)
				)
				(justify right)
			)
		)
		(property "Value" "C_100n_0402"
			(at 173.99 218.44 0)
			(effects
				(font
					(size 1.27 1.27)
					(thickness 0.15)
				)
				(justify left bottom)
				(hide yes)
			)
		)
		(property "Footprint" "antmicro-footprints:C_0402_1005Metric"
			(at 171.45 218.44 0)
			(effects
				(font
					(size 1.27 1.27)
					(thickness 0.15)
				)
				(justify left bottom)
				(hide yes)
			)
		)
		(property "Datasheet" "https://www.murata.com/products/productdetail?partno=GRM155R61H104KE14%23"
			(at 168.91 218.44 0)
			(effects
				(font
					(size 1.27 1.27)
					(thickness 0.15)
				)
				(justify left bottom)
				(hide yes)
			)
		)
		(property "Description" ""
			(at 184.15 238.76 0)
			(effects
				(font
					(size 1.27 1.27)
				)
			)
		)
		(property "Manufacturer" "Murata"
			(at 163.83 218.44 0)
			(effects
				(font
					(size 1.27 1.27)
					(thickness 0.15)
				)
				(justify left bottom)
				(hide yes)
			)
		)
		(property "MPN" "GRM155R61H104KE14D"
			(at 166.37 218.44 0)
			(effects
				(font
					(size 1.27 1.27)
					(thickness 0.15)
				)
				(justify left bottom)
				(hide yes)
			)
		)
		(property "Val" "100n"
			(at 183.515 238.125 90)
			(effects
				(font
					(size 1.27 1.27)
					(thickness 0.15)
				)
				(justify right)
			)
		)
		(property "License" "Apache-2.0"
			(at 161.29 218.44 0)
			(effects
				(font
					(size 1.27 1.27)
					(thickness 0.15)
				)
				(justify left bottom)
				(hide yes)
			)
		)
		(property "Author" "Antmicro"
			(at 158.75 218.44 0)
			(effects
				(font
					(size 1.27 1.27)
					(thickness 0.15)
				)
				(justify left bottom)
				(hide yes)
			)
		)
		(property "Voltage" "50V"
			(at 156.21 218.44 0)
			(effects
				(font
					(size 1.27 1.27)
				)
				(justify left bottom)
				(hide yes)
			)
		)
		(property "Dielectric" "X5R"
			(at 153.67 218.44 0)
			(effects
				(font
					(size 1.27 1.27)
				)
				(justify left bottom)
				(hide yes)
			)
		)
		(pin "1"
		)
		(pin "2"
		)
		(instances
			(project "k410t-devboard"
				(path ""
					(reference "C136")
					(unit 1)
				)
			)
		)
	)
	(symbol
		(lib_id "antmicroCapacitors0603:C_47u_0603")
		(at 130.81 238.76 270)
		(mirror x)
		(unit 1)
		(exclude_from_sim no)
		(in_bom yes)
		(on_board yes)
		(dnp no)
		(property "Reference" "C386"
			(at 130.175 234.315 90)
			(effects
				(font
					(size 1.27 1.27)
				)
				(justify right)
			)
		)
		(property "Value" "C_47u_0603"
			(at 120.65 218.44 0)
			(effects
				(font
					(size 1.27 1.27)
					(thickness 0.15)
				)
				(justify left bottom)
				(hide yes)
			)
		)
		(property "Footprint" "antmicro-footprints:C_0603_1608Metric"
			(at 118.11 218.44 0)
			(effects
				(font
					(size 1.27 1.27)
					(thickness 0.15)
				)
				(justify left bottom)
				(hide yes)
			)
		)
		(property "Datasheet" "https://www.murata.com/products/productdetail?partno=GRM188R60J476ME15%23"
			(at 115.57 218.44 0)
			(effects
				(font
					(size 1.27 1.27)
					(thickness 0.15)
				)
				(justify left bottom)
				(hide yes)
			)
		)
		(property "Description" ""
			(at 130.81 238.76 0)
			(effects
				(font
					(size 1.27 1.27)
				)
			)
		)
		(property "Manufacturer" "Murata"
			(at 110.49 218.44 0)
			(effects
				(font
					(size 1.27 1.27)
					(thickness 0.15)
				)
				(justify left bottom)
				(hide yes)
			)
		)
		(property "MPN" "GRM188R60J476ME15D"
			(at 113.03 218.44 0)
			(effects
				(font
					(size 1.27 1.27)
					(thickness 0.15)
				)
				(justify left bottom)
				(hide yes)
			)
		)
		(property "Val" "47u"
			(at 130.175 238.125 90)
			(effects
				(font
					(size 1.27 1.27)
					(thickness 0.15)
				)
				(justify right)
			)
		)
		(property "License" "Apache-2.0"
			(at 107.95 218.44 0)
			(effects
				(font
					(size 1.27 1.27)
					(thickness 0.15)
				)
				(justify left bottom)
				(hide yes)
			)
		)
		(property "Author" "Antmicro"
			(at 105.41 218.44 0)
			(effects
				(font
					(size 1.27 1.27)
					(thickness 0.15)
				)
				(justify left bottom)
				(hide yes)
			)
		)
		(property "Voltage" ""
			(at 102.87 218.44 0)
			(effects
				(font
					(size 1.27 1.27)
				)
				(justify left bottom)
				(hide yes)
			)
		)
		(property "Dielectric" ""
			(at 100.33 218.44 0)
			(effects
				(font
					(size 1.27 1.27)
				)
				(justify left bottom)
				(hide yes)
			)
		)
		(pin "1"
		)
		(pin "2"
		)
		(instances
			(project "k410t-devboard"
				(path ""
					(reference "C386")
					(unit 1)
				)
			)
		)
	)
	(symbol
		(lib_id "antmicroCapacitors0402:C_100n_0402")
		(at 222.25 151.13 90)
		(unit 1)
		(exclude_from_sim no)
		(in_bom yes)
		(on_board yes)
		(dnp no)
		(property "Reference" "C58"
			(at 222.885 146.685 90)
			(effects
				(font
					(size 1.27 1.27)
				)
				(justify right)
			)
		)
		(property "Value" "C_100n_0402"
			(at 232.41 130.81 0)
			(effects
				(font
					(size 1.27 1.27)
					(thickness 0.15)
				)
				(justify left bottom)
				(hide yes)
			)
		)
		(property "Footprint" "antmicro-footprints:C_0402_1005Metric"
			(at 234.95 130.81 0)
			(effects
				(font
					(size 1.27 1.27)
					(thickness 0.15)
				)
				(justify left bottom)
				(hide yes)
			)
		)
		(property "Datasheet" "https://www.murata.com/products/productdetail?partno=GRM155R61H104KE14%23"
			(at 237.49 130.81 0)
			(effects
				(font
					(size 1.27 1.27)
					(thickness 0.15)
				)
				(justify left bottom)
				(hide yes)
			)
		)
		(property "Description" ""
			(at 222.25 151.13 0)
			(effects
				(font
					(size 1.27 1.27)
				)
			)
		)
		(property "Manufacturer" "Murata"
			(at 242.57 130.81 0)
			(effects
				(font
					(size 1.27 1.27)
					(thickness 0.15)
				)
				(justify left bottom)
				(hide yes)
			)
		)
		(property "MPN" "GRM155R61H104KE14D"
			(at 240.03 130.81 0)
			(effects
				(font
					(size 1.27 1.27)
					(thickness 0.15)
				)
				(justify left bottom)
				(hide yes)
			)
		)
		(property "Val" "100n"
			(at 222.885 150.495 90)
			(effects
				(font
					(size 1.27 1.27)
					(thickness 0.15)
				)
				(justify right)
			)
		)
		(property "License" "Apache-2.0"
			(at 245.11 130.81 0)
			(effects
				(font
					(size 1.27 1.27)
					(thickness 0.15)
				)
				(justify left bottom)
				(hide yes)
			)
		)
		(property "Author" "Antmicro"
			(at 247.65 130.81 0)
			(effects
				(font
					(size 1.27 1.27)
					(thickness 0.15)
				)
				(justify left bottom)
				(hide yes)
			)
		)
		(property "Voltage" "50V"
			(at 250.19 130.81 0)
			(effects
				(font
					(size 1.27 1.27)
				)
				(justify left bottom)
				(hide yes)
			)
		)
		(property "Dielectric" "X5R"
			(at 252.73 130.81 0)
			(effects
				(font
					(size 1.27 1.27)
				)
				(justify left bottom)
				(hide yes)
			)
		)
		(pin "1"
		)
		(pin "2"
		)
		(instances
			(project "k410t-devboard"
				(path ""
					(reference "C58")
					(unit 1)
				)
			)
		)
	)
	(symbol
		(lib_id "antmicroCapacitorsmisc:C_100n_0201")
		(at 214.63 201.93 270)
		(mirror x)
		(unit 1)
		(exclude_from_sim no)
		(in_bom yes)
		(on_board yes)
		(dnp no)
		(property "Reference" "C74"
			(at 213.995 197.485 90)
			(effects
				(font
					(size 1.27 1.27)
				)
				(justify right)
			)
		)
		(property "Value" "C_100n_0201"
			(at 204.47 181.61 0)
			(effects
				(font
					(size 1.27 1.27)
					(thickness 0.15)
				)
				(justify left bottom)
				(hide yes)
			)
		)
		(property "Footprint" "antmicro-footprints:C_0201"
			(at 201.93 181.61 0)
			(effects
				(font
					(size 1.27 1.27)
					(thickness 0.15)
				)
				(justify left bottom)
				(hide yes)
			)
		)
		(property "Datasheet" "https://www.yageo.com/en/Chart/Download/pdf/CC0201KRX6S5BB104"
			(at 199.39 181.61 0)
			(effects
				(font
					(size 1.27 1.27)
					(thickness 0.15)
				)
				(justify left bottom)
				(hide yes)
			)
		)
		(property "Description" ""
			(at 214.63 201.93 0)
			(effects
				(font
					(size 1.27 1.27)
				)
			)
		)
		(property "Manufacturer" "YAGEO"
			(at 194.31 181.61 0)
			(effects
				(font
					(size 1.27 1.27)
					(thickness 0.15)
				)
				(justify left bottom)
				(hide yes)
			)
		)
		(property "MPN" "CC0201KRX6S5BB104"
			(at 196.85 181.61 0)
			(effects
				(font
					(size 1.27 1.27)
					(thickness 0.15)
				)
				(justify left bottom)
				(hide yes)
			)
		)
		(property "Val" "100n"
			(at 213.995 201.295 90)
			(effects
				(font
					(size 1.27 1.27)
					(thickness 0.15)
				)
				(justify right)
			)
		)
		(property "License" "Apache-2.0"
			(at 191.77 181.61 0)
			(effects
				(font
					(size 1.27 1.27)
					(thickness 0.15)
				)
				(justify left bottom)
				(hide yes)
			)
		)
		(property "Author" "Antmicro"
			(at 189.23 181.61 0)
			(effects
				(font
					(size 1.27 1.27)
					(thickness 0.15)
				)
				(justify left bottom)
				(hide yes)
			)
		)
		(property "Voltage" ""
			(at 186.69 181.61 0)
			(effects
				(font
					(size 1.27 1.27)
				)
				(justify left bottom)
				(hide yes)
			)
		)
		(property "Dielectric" ""
			(at 184.15 181.61 0)
			(effects
				(font
					(size 1.27 1.27)
				)
				(justify left bottom)
				(hide yes)
			)
		)
		(pin "1"
		)
		(pin "2"
		)
		(instances
			(project "k410t-devboard"
				(path ""
					(reference "C74")
					(unit 1)
				)
			)
		)
	)
	(symbol
		(lib_id "antmicropower:GND")
		(at 123.19 224.79 0)
		(unit 1)
		(exclude_from_sim no)
		(in_bom yes)
		(on_board yes)
		(dnp no)
		(property "Reference" "#PWR0488"
			(at 123.19 231.14 0)
			(effects
				(font
					(size 1.27 1.27)
				)
				(hide yes)
			)
		)
		(property "Value" "GND"
			(at 123.19 228.6 0)
			(effects
				(font
					(size 1.27 1.27)
				)
			)
		)
		(property "Footprint" ""
			(at 132.08 232.41 0)
			(effects
				(font
					(size 1.27 1.27)
					(thickness 0.15)
				)
				(justify left bottom)
				(hide yes)
			)
		)
		(property "Datasheet" ""
			(at 132.08 237.49 0)
			(effects
				(font
					(size 1.27 1.27)
					(thickness 0.15)
				)
				(justify left bottom)
				(hide yes)
			)
		)
		(property "Description" ""
			(at 123.19 224.79 0)
			(effects
				(font
					(size 1.27 1.27)
				)
			)
		)
		(property "Author" "Antmicro"
			(at 132.08 232.41 0)
			(effects
				(font
					(size 1.27 1.27)
					(thickness 0.15)
				)
				(justify left bottom)
				(hide yes)
			)
		)
		(property "License" "Apache-2.0"
			(at 132.08 234.95 0)
			(effects
				(font
					(size 1.27 1.27)
					(thickness 0.15)
				)
				(justify left bottom)
				(hide yes)
			)
		)
		(pin "1"
		)
		(instances
			(project "k410t-devboard"
				(path ""
					(reference "#PWR0488")
					(unit 1)
				)
			)
		)
	)
	(symbol
		(lib_id "antmicroCapacitorsmisc:C_4u7_0201")
		(at 161.29 201.93 270)
		(mirror x)
		(unit 1)
		(exclude_from_sim no)
		(in_bom yes)
		(on_board yes)
		(dnp no)
		(property "Reference" "C48"
			(at 160.655 197.485 90)
			(effects
				(font
					(size 1.27 1.27)
				)
				(justify right)
			)
		)
		(property "Value" "C_4u7_0201"
			(at 151.13 181.61 0)
			(effects
				(font
					(size 1.27 1.27)
					(thickness 0.15)
				)
				(justify left bottom)
				(hide yes)
			)
		)
		(property "Footprint" "antmicro-footprints:C_0201"
			(at 148.59 181.61 0)
			(effects
				(font
					(size 1.27 1.27)
					(thickness 0.15)
				)
				(justify left bottom)
				(hide yes)
			)
		)
		(property "Datasheet" "https://www.murata.com/products/productdetail?partno=GRM035R60J475ME15%23"
			(at 146.05 181.61 0)
			(effects
				(font
					(size 1.27 1.27)
					(thickness 0.15)
				)
				(justify left bottom)
				(hide yes)
			)
		)
		(property "Description" ""
			(at 161.29 201.93 0)
			(effects
				(font
					(size 1.27 1.27)
				)
			)
		)
		(property "Manufacturer" "Murata"
			(at 140.97 181.61 0)
			(effects
				(font
					(size 1.27 1.27)
					(thickness 0.15)
				)
				(justify left bottom)
				(hide yes)
			)
		)
		(property "MPN" "GRM035R60J475ME15D"
			(at 143.51 181.61 0)
			(effects
				(font
					(size 1.27 1.27)
					(thickness 0.15)
				)
				(justify left bottom)
				(hide yes)
			)
		)
		(property "Val" "4u7"
			(at 160.655 201.295 90)
			(effects
				(font
					(size 1.27 1.27)
					(thickness 0.15)
				)
				(justify right)
			)
		)
		(property "License" "Apache-2.0"
			(at 138.43 181.61 0)
			(effects
				(font
					(size 1.27 1.27)
					(thickness 0.15)
				)
				(justify left bottom)
				(hide yes)
			)
		)
		(property "Author" "Antmicro"
			(at 135.89 181.61 0)
			(effects
				(font
					(size 1.27 1.27)
					(thickness 0.15)
				)
				(justify left bottom)
				(hide yes)
			)
		)
		(property "Voltage" ""
			(at 133.35 181.61 0)
			(effects
				(font
					(size 1.27 1.27)
				)
				(justify left bottom)
				(hide yes)
			)
		)
		(property "Dielectric" ""
			(at 130.81 181.61 0)
			(effects
				(font
					(size 1.27 1.27)
				)
				(justify left bottom)
				(hide yes)
			)
		)
		(pin "1"
		)
		(pin "2"
		)
		(instances
			(project "k410t-devboard"
				(path ""
					(reference "C48")
					(unit 1)
				)
			)
		)
	)
	(symbol
		(lib_id "antmicroCapacitorsmisc:C_100n_0201")
		(at 203.2 76.2 90)
		(unit 1)
		(exclude_from_sim no)
		(in_bom yes)
		(on_board yes)
		(dnp no)
		(property "Reference" "C152"
			(at 203.835 71.755 90)
			(effects
				(font
					(size 1.27 1.27)
				)
				(justify right)
			)
		)
		(property "Value" "C_100n_0201"
			(at 213.36 55.88 0)
			(effects
				(font
					(size 1.27 1.27)
					(thickness 0.15)
				)
				(justify left bottom)
				(hide yes)
			)
		)
		(property "Footprint" "antmicro-footprints:C_0201"
			(at 215.9 55.88 0)
			(effects
				(font
					(size 1.27 1.27)
					(thickness 0.15)
				)
				(justify left bottom)
				(hide yes)
			)
		)
		(property "Datasheet" "https://www.yageo.com/en/Chart/Download/pdf/CC0201KRX6S5BB104"
			(at 218.44 55.88 0)
			(effects
				(font
					(size 1.27 1.27)
					(thickness 0.15)
				)
				(justify left bottom)
				(hide yes)
			)
		)
		(property "Description" ""
			(at 203.2 76.2 0)
			(effects
				(font
					(size 1.27 1.27)
				)
			)
		)
		(property "Manufacturer" "YAGEO"
			(at 223.52 55.88 0)
			(effects
				(font
					(size 1.27 1.27)
					(thickness 0.15)
				)
				(justify left bottom)
				(hide yes)
			)
		)
		(property "MPN" "CC0201KRX6S5BB104"
			(at 220.98 55.88 0)
			(effects
				(font
					(size 1.27 1.27)
					(thickness 0.15)
				)
				(justify left bottom)
				(hide yes)
			)
		)
		(property "Val" "100n"
			(at 203.835 75.565 90)
			(effects
				(font
					(size 1.27 1.27)
					(thickness 0.15)
				)
				(justify right)
			)
		)
		(property "License" "Apache-2.0"
			(at 226.06 55.88 0)
			(effects
				(font
					(size 1.27 1.27)
					(thickness 0.15)
				)
				(justify left bottom)
				(hide yes)
			)
		)
		(property "Author" "Antmicro"
			(at 228.6 55.88 0)
			(effects
				(font
					(size 1.27 1.27)
					(thickness 0.15)
				)
				(justify left bottom)
				(hide yes)
			)
		)
		(property "Voltage" ""
			(at 231.14 55.88 0)
			(effects
				(font
					(size 1.27 1.27)
				)
				(justify left bottom)
				(hide yes)
			)
		)
		(property "Dielectric" ""
			(at 233.68 55.88 0)
			(effects
				(font
					(size 1.27 1.27)
				)
				(justify left bottom)
				(hide yes)
			)
		)
		(pin "1"
		)
		(pin "2"
		)
		(instances
			(project "k410t-devboard"
				(path ""
					(reference "C152")
					(unit 1)
				)
			)
		)
	)
	(symbol
		(lib_id "antmicroCapacitors0402:C_100n_0402")
		(at 191.77 238.76 270)
		(mirror x)
		(unit 1)
		(exclude_from_sim no)
		(in_bom yes)
		(on_board yes)
		(dnp no)
		(property "Reference" "C134"
			(at 191.135 234.315 90)
			(effects
				(font
					(size 1.27 1.27)
				)
				(justify right)
			)
		)
		(property "Value" "C_100n_0402"
			(at 181.61 218.44 0)
			(effects
				(font
					(size 1.27 1.27)
					(thickness 0.15)
				)
				(justify left bottom)
				(hide yes)
			)
		)
		(property "Footprint" "antmicro-footprints:C_0402_1005Metric"
			(at 179.07 218.44 0)
			(effects
				(font
					(size 1.27 1.27)
					(thickness 0.15)
				)
				(justify left bottom)
				(hide yes)
			)
		)
		(property "Datasheet" "https://www.murata.com/products/productdetail?partno=GRM155R61H104KE14%23"
			(at 176.53 218.44 0)
			(effects
				(font
					(size 1.27 1.27)
					(thickness 0.15)
				)
				(justify left bottom)
				(hide yes)
			)
		)
		(property "Description" ""
			(at 191.77 238.76 0)
			(effects
				(font
					(size 1.27 1.27)
				)
			)
		)
		(property "Manufacturer" "Murata"
			(at 171.45 218.44 0)
			(effects
				(font
					(size 1.27 1.27)
					(thickness 0.15)
				)
				(justify left bottom)
				(hide yes)
			)
		)
		(property "MPN" "GRM155R61H104KE14D"
			(at 173.99 218.44 0)
			(effects
				(font
					(size 1.27 1.27)
					(thickness 0.15)
				)
				(justify left bottom)
				(hide yes)
			)
		)
		(property "Val" "100n"
			(at 191.135 238.125 90)
			(effects
				(font
					(size 1.27 1.27)
					(thickness 0.15)
				)
				(justify right)
			)
		)
		(property "License" "Apache-2.0"
			(at 168.91 218.44 0)
			(effects
				(font
					(size 1.27 1.27)
					(thickness 0.15)
				)
				(justify left bottom)
				(hide yes)
			)
		)
		(property "Author" "Antmicro"
			(at 166.37 218.44 0)
			(effects
				(font
					(size 1.27 1.27)
					(thickness 0.15)
				)
				(justify left bottom)
				(hide yes)
			)
		)
		(property "Voltage" "50V"
			(at 163.83 218.44 0)
			(effects
				(font
					(size 1.27 1.27)
				)
				(justify left bottom)
				(hide yes)
			)
		)
		(property "Dielectric" "X5R"
			(at 161.29 218.44 0)
			(effects
				(font
					(size 1.27 1.27)
				)
				(justify left bottom)
				(hide yes)
			)
		)
		(pin "1"
		)
		(pin "2"
		)
		(instances
			(project "k410t-devboard"
				(path ""
					(reference "C134")
					(unit 1)
				)
			)
		)
	)
	(symbol
		(lib_id "antmicroCapacitorsmisc:C_4u7_0201")
		(at 157.48 76.2 90)
		(unit 1)
		(exclude_from_sim no)
		(in_bom yes)
		(on_board yes)
		(dnp no)
		(property "Reference" "C163"
			(at 158.115 71.755 90)
			(effects
				(font
					(size 1.27 1.27)
				)
				(justify right)
			)
		)
		(property "Value" "C_4u7_0201"
			(at 167.64 55.88 0)
			(effects
				(font
					(size 1.27 1.27)
					(thickness 0.15)
				)
				(justify left bottom)
				(hide yes)
			)
		)
		(property "Footprint" "antmicro-footprints:C_0201"
			(at 170.18 55.88 0)
			(effects
				(font
					(size 1.27 1.27)
					(thickness 0.15)
				)
				(justify left bottom)
				(hide yes)
			)
		)
		(property "Datasheet" "https://www.murata.com/products/productdetail?partno=GRM035R60J475ME15%23"
			(at 172.72 55.88 0)
			(effects
				(font
					(size 1.27 1.27)
					(thickness 0.15)
				)
				(justify left bottom)
				(hide yes)
			)
		)
		(property "Description" ""
			(at 157.48 76.2 0)
			(effects
				(font
					(size 1.27 1.27)
				)
			)
		)
		(property "Manufacturer" "Murata"
			(at 177.8 55.88 0)
			(effects
				(font
					(size 1.27 1.27)
					(thickness 0.15)
				)
				(justify left bottom)
				(hide yes)
			)
		)
		(property "MPN" "GRM035R60J475ME15D"
			(at 175.26 55.88 0)
			(effects
				(font
					(size 1.27 1.27)
					(thickness 0.15)
				)
				(justify left bottom)
				(hide yes)
			)
		)
		(property "Val" "4u7"
			(at 158.115 75.565 90)
			(effects
				(font
					(size 1.27 1.27)
					(thickness 0.15)
				)
				(justify right)
			)
		)
		(property "License" "Apache-2.0"
			(at 180.34 55.88 0)
			(effects
				(font
					(size 1.27 1.27)
					(thickness 0.15)
				)
				(justify left bottom)
				(hide yes)
			)
		)
		(property "Author" "Antmicro"
			(at 182.88 55.88 0)
			(effects
				(font
					(size 1.27 1.27)
					(thickness 0.15)
				)
				(justify left bottom)
				(hide yes)
			)
		)
		(property "Voltage" ""
			(at 185.42 55.88 0)
			(effects
				(font
					(size 1.27 1.27)
				)
				(justify left bottom)
				(hide yes)
			)
		)
		(property "Dielectric" ""
			(at 187.96 55.88 0)
			(effects
				(font
					(size 1.27 1.27)
				)
				(justify left bottom)
				(hide yes)
			)
		)
		(pin "1"
		)
		(pin "2"
		)
		(instances
			(project "k410t-devboard"
				(path ""
					(reference "C163")
					(unit 1)
				)
			)
		)
	)
	(symbol
		(lib_id "antmicroCapacitorsmisc:C_100n_0201")
		(at 226.06 76.2 90)
		(unit 1)
		(exclude_from_sim no)
		(in_bom yes)
		(on_board yes)
		(dnp no)
		(property "Reference" "C158"
			(at 226.695 71.755 90)
			(effects
				(font
					(size 1.27 1.27)
				)
				(justify right)
			)
		)
		(property "Value" "C_100n_0201"
			(at 236.22 55.88 0)
			(effects
				(font
					(size 1.27 1.27)
					(thickness 0.15)
				)
				(justify left bottom)
				(hide yes)
			)
		)
		(property "Footprint" "antmicro-footprints:C_0201"
			(at 238.76 55.88 0)
			(effects
				(font
					(size 1.27 1.27)
					(thickness 0.15)
				)
				(justify left bottom)
				(hide yes)
			)
		)
		(property "Datasheet" "https://www.yageo.com/en/Chart/Download/pdf/CC0201KRX6S5BB104"
			(at 241.3 55.88 0)
			(effects
				(font
					(size 1.27 1.27)
					(thickness 0.15)
				)
				(justify left bottom)
				(hide yes)
			)
		)
		(property "Description" ""
			(at 226.06 76.2 0)
			(effects
				(font
					(size 1.27 1.27)
				)
			)
		)
		(property "Manufacturer" "YAGEO"
			(at 246.38 55.88 0)
			(effects
				(font
					(size 1.27 1.27)
					(thickness 0.15)
				)
				(justify left bottom)
				(hide yes)
			)
		)
		(property "MPN" "CC0201KRX6S5BB104"
			(at 243.84 55.88 0)
			(effects
				(font
					(size 1.27 1.27)
					(thickness 0.15)
				)
				(justify left bottom)
				(hide yes)
			)
		)
		(property "Val" "100n"
			(at 226.695 75.565 90)
			(effects
				(font
					(size 1.27 1.27)
					(thickness 0.15)
				)
				(justify right)
			)
		)
		(property "License" "Apache-2.0"
			(at 248.92 55.88 0)
			(effects
				(font
					(size 1.27 1.27)
					(thickness 0.15)
				)
				(justify left bottom)
				(hide yes)
			)
		)
		(property "Author" "Antmicro"
			(at 251.46 55.88 0)
			(effects
				(font
					(size 1.27 1.27)
					(thickness 0.15)
				)
				(justify left bottom)
				(hide yes)
			)
		)
		(property "Voltage" ""
			(at 254 55.88 0)
			(effects
				(font
					(size 1.27 1.27)
				)
				(justify left bottom)
				(hide yes)
			)
		)
		(property "Dielectric" ""
			(at 256.54 55.88 0)
			(effects
				(font
					(size 1.27 1.27)
				)
				(justify left bottom)
				(hide yes)
			)
		)
		(pin "1"
		)
		(pin "2"
		)
		(instances
			(project "k410t-devboard"
				(path ""
					(reference "C158")
					(unit 1)
				)
			)
		)
	)
	(symbol
		(lib_id "antmicroCapacitors0402:C_100n_0402")
		(at 226.06 31.75 90)
		(mirror x)
		(unit 1)
		(exclude_from_sim no)
		(in_bom yes)
		(on_board yes)
		(dnp no)
		(property "Reference" "C119"
			(at 226.695 32.385 90)
			(effects
				(font
					(size 1.27 1.27)
				)
				(justify right)
			)
		)
		(property "Value" "C_100n_0402"
			(at 236.22 52.07 0)
			(effects
				(font
					(size 1.27 1.27)
					(thickness 0.15)
				)
				(justify left bottom)
				(hide yes)
			)
		)
		(property "Footprint" "antmicro-footprints:C_0402_1005Metric"
			(at 238.76 52.07 0)
			(effects
				(font
					(size 1.27 1.27)
					(thickness 0.15)
				)
				(justify left bottom)
				(hide yes)
			)
		)
		(property "Datasheet" "https://www.murata.com/products/productdetail?partno=GRM155R61H104KE14%23"
			(at 241.3 52.07 0)
			(effects
				(font
					(size 1.27 1.27)
					(thickness 0.15)
				)
				(justify left bottom)
				(hide yes)
			)
		)
		(property "Description" ""
			(at 226.06 31.75 0)
			(effects
				(font
					(size 1.27 1.27)
				)
			)
		)
		(property "Manufacturer" "Murata"
			(at 246.38 52.07 0)
			(effects
				(font
					(size 1.27 1.27)
					(thickness 0.15)
				)
				(justify left bottom)
				(hide yes)
			)
		)
		(property "MPN" "GRM155R61H104KE14D"
			(at 243.84 52.07 0)
			(effects
				(font
					(size 1.27 1.27)
					(thickness 0.15)
				)
				(justify left bottom)
				(hide yes)
			)
		)
		(property "Val" "100n"
			(at 226.695 36.195 90)
			(effects
				(font
					(size 1.27 1.27)
					(thickness 0.15)
				)
				(justify right)
			)
		)
		(property "License" "Apache-2.0"
			(at 248.92 52.07 0)
			(effects
				(font
					(size 1.27 1.27)
					(thickness 0.15)
				)
				(justify left bottom)
				(hide yes)
			)
		)
		(property "Author" "Antmicro"
			(at 251.46 52.07 0)
			(effects
				(font
					(size 1.27 1.27)
					(thickness 0.15)
				)
				(justify left bottom)
				(hide yes)
			)
		)
		(property "Voltage" "50V"
			(at 254 52.07 0)
			(effects
				(font
					(size 1.27 1.27)
				)
				(justify left bottom)
				(hide yes)
			)
		)
		(property "Dielectric" "X5R"
			(at 256.54 52.07 0)
			(effects
				(font
					(size 1.27 1.27)
				)
				(justify left bottom)
				(hide yes)
			)
		)
		(pin "1"
		)
		(pin "2"
		)
		(instances
			(project "k410t-devboard"
				(path ""
					(reference "C119")
					(unit 1)
				)
			)
		)
	)
	(symbol
		(lib_id "antmicropower:+1V2_MGTAVTT")
		(at 237.49 64.77 0)
		(mirror y)
		(unit 1)
		(exclude_from_sim no)
		(in_bom yes)
		(on_board yes)
		(dnp no)
		(property "Reference" "#PWR035"
			(at 237.49 68.58 0)
			(effects
				(font
					(size 1.27 1.27)
				)
				(hide yes)
			)
		)
		(property "Value" "+1V2_MGTAVTT"
			(at 237.49 60.96 0)
			(effects
				(font
					(size 1.27 1.27)
				)
			)
		)
		(property "Footprint" ""
			(at 237.49 64.77 0)
			(effects
				(font
					(size 1.27 1.27)
				)
				(hide yes)
			)
		)
		(property "Datasheet" ""
			(at 237.49 64.77 0)
			(effects
				(font
					(size 1.27 1.27)
				)
				(hide yes)
			)
		)
		(property "Description" ""
			(at 237.49 64.77 0)
			(effects
				(font
					(size 1.27 1.27)
				)
			)
		)
		(pin "1"
		)
		(instances
			(project "k410t-devboard"
				(path ""
					(reference "#PWR035")
					(unit 1)
				)
			)
		)
	)
	(symbol
		(lib_id "antmicropower:GND")
		(at 138.43 205.74 0)
		(unit 1)
		(exclude_from_sim no)
		(in_bom yes)
		(on_board yes)
		(dnp no)
		(property "Reference" "#PWR0494"
			(at 138.43 212.09 0)
			(effects
				(font
					(size 1.27 1.27)
				)
				(hide yes)
			)
		)
		(property "Value" "GND"
			(at 138.43 209.55 0)
			(effects
				(font
					(size 1.27 1.27)
				)
			)
		)
		(property "Footprint" ""
			(at 147.32 213.36 0)
			(effects
				(font
					(size 1.27 1.27)
					(thickness 0.15)
				)
				(justify left bottom)
				(hide yes)
			)
		)
		(property "Datasheet" ""
			(at 147.32 218.44 0)
			(effects
				(font
					(size 1.27 1.27)
					(thickness 0.15)
				)
				(justify left bottom)
				(hide yes)
			)
		)
		(property "Description" ""
			(at 138.43 205.74 0)
			(effects
				(font
					(size 1.27 1.27)
				)
			)
		)
		(property "Author" "Antmicro"
			(at 147.32 213.36 0)
			(effects
				(font
					(size 1.27 1.27)
					(thickness 0.15)
				)
				(justify left bottom)
				(hide yes)
			)
		)
		(property "License" "Apache-2.0"
			(at 147.32 215.9 0)
			(effects
				(font
					(size 1.27 1.27)
					(thickness 0.15)
				)
				(justify left bottom)
				(hide yes)
			)
		)
		(pin "1"
		)
		(instances
			(project "k410t-devboard"
				(path ""
					(reference "#PWR0494")
					(unit 1)
				)
			)
		)
	)
	(symbol
		(lib_id "antmicroCapacitorsmisc:C_100n_0201")
		(at 222.25 201.93 270)
		(mirror x)
		(unit 1)
		(exclude_from_sim no)
		(in_bom yes)
		(on_board yes)
		(dnp no)
		(property "Reference" "C65"
			(at 221.615 197.485 90)
			(effects
				(font
					(size 1.27 1.27)
				)
				(justify right)
			)
		)
		(property "Value" "C_100n_0201"
			(at 212.09 181.61 0)
			(effects
				(font
					(size 1.27 1.27)
					(thickness 0.15)
				)
				(justify left bottom)
				(hide yes)
			)
		)
		(property "Footprint" "antmicro-footprints:C_0201"
			(at 209.55 181.61 0)
			(effects
				(font
					(size 1.27 1.27)
					(thickness 0.15)
				)
				(justify left bottom)
				(hide yes)
			)
		)
		(property "Datasheet" "https://www.yageo.com/en/Chart/Download/pdf/CC0201KRX6S5BB104"
			(at 207.01 181.61 0)
			(effects
				(font
					(size 1.27 1.27)
					(thickness 0.15)
				)
				(justify left bottom)
				(hide yes)
			)
		)
		(property "Description" ""
			(at 222.25 201.93 0)
			(effects
				(font
					(size 1.27 1.27)
				)
			)
		)
		(property "Manufacturer" "YAGEO"
			(at 201.93 181.61 0)
			(effects
				(font
					(size 1.27 1.27)
					(thickness 0.15)
				)
				(justify left bottom)
				(hide yes)
			)
		)
		(property "MPN" "CC0201KRX6S5BB104"
			(at 204.47 181.61 0)
			(effects
				(font
					(size 1.27 1.27)
					(thickness 0.15)
				)
				(justify left bottom)
				(hide yes)
			)
		)
		(property "Val" "100n"
			(at 221.615 201.295 90)
			(effects
				(font
					(size 1.27 1.27)
					(thickness 0.15)
				)
				(justify right)
			)
		)
		(property "License" "Apache-2.0"
			(at 199.39 181.61 0)
			(effects
				(font
					(size 1.27 1.27)
					(thickness 0.15)
				)
				(justify left bottom)
				(hide yes)
			)
		)
		(property "Author" "Antmicro"
			(at 196.85 181.61 0)
			(effects
				(font
					(size 1.27 1.27)
					(thickness 0.15)
				)
				(justify left bottom)
				(hide yes)
			)
		)
		(property "Voltage" ""
			(at 194.31 181.61 0)
			(effects
				(font
					(size 1.27 1.27)
				)
				(justify left bottom)
				(hide yes)
			)
		)
		(property "Dielectric" ""
			(at 191.77 181.61 0)
			(effects
				(font
					(size 1.27 1.27)
				)
				(justify left bottom)
				(hide yes)
			)
		)
		(pin "1"
		)
		(pin "2"
		)
		(instances
			(project "k410t-devboard"
				(path ""
					(reference "C65")
					(unit 1)
				)
			)
		)
	)
	(symbol
		(lib_id "antmicroCapacitors0402:C_100n_0402")
		(at 195.58 31.75 90)
		(mirror x)
		(unit 1)
		(exclude_from_sim no)
		(in_bom yes)
		(on_board yes)
		(dnp no)
		(property "Reference" "C103"
			(at 196.215 32.385 90)
			(effects
				(font
					(size 1.27 1.27)
				)
				(justify right)
			)
		)
		(property "Value" "C_100n_0402"
			(at 205.74 52.07 0)
			(effects
				(font
					(size 1.27 1.27)
					(thickness 0.15)
				)
				(justify left bottom)
				(hide yes)
			)
		)
		(property "Footprint" "antmicro-footprints:C_0402_1005Metric"
			(at 208.28 52.07 0)
			(effects
				(font
					(size 1.27 1.27)
					(thickness 0.15)
				)
				(justify left bottom)
				(hide yes)
			)
		)
		(property "Datasheet" "https://www.murata.com/products/productdetail?partno=GRM155R61H104KE14%23"
			(at 210.82 52.07 0)
			(effects
				(font
					(size 1.27 1.27)
					(thickness 0.15)
				)
				(justify left bottom)
				(hide yes)
			)
		)
		(property "Description" ""
			(at 195.58 31.75 0)
			(effects
				(font
					(size 1.27 1.27)
				)
			)
		)
		(property "Manufacturer" "Murata"
			(at 215.9 52.07 0)
			(effects
				(font
					(size 1.27 1.27)
					(thickness 0.15)
				)
				(justify left bottom)
				(hide yes)
			)
		)
		(property "MPN" "GRM155R61H104KE14D"
			(at 213.36 52.07 0)
			(effects
				(font
					(size 1.27 1.27)
					(thickness 0.15)
				)
				(justify left bottom)
				(hide yes)
			)
		)
		(property "Val" "100n"
			(at 196.215 36.195 90)
			(effects
				(font
					(size 1.27 1.27)
					(thickness 0.15)
				)
				(justify right)
			)
		)
		(property "License" "Apache-2.0"
			(at 218.44 52.07 0)
			(effects
				(font
					(size 1.27 1.27)
					(thickness 0.15)
				)
				(justify left bottom)
				(hide yes)
			)
		)
		(property "Author" "Antmicro"
			(at 220.98 52.07 0)
			(effects
				(font
					(size 1.27 1.27)
					(thickness 0.15)
				)
				(justify left bottom)
				(hide yes)
			)
		)
		(property "Voltage" "50V"
			(at 223.52 52.07 0)
			(effects
				(font
					(size 1.27 1.27)
				)
				(justify left bottom)
				(hide yes)
			)
		)
		(property "Dielectric" "X5R"
			(at 226.06 52.07 0)
			(effects
				(font
					(size 1.27 1.27)
				)
				(justify left bottom)
				(hide yes)
			)
		)
		(pin "1"
		)
		(pin "2"
		)
		(instances
			(project "k410t-devboard"
				(path ""
					(reference "C103")
					(unit 1)
				)
			)
		)
	)
	(symbol
		(lib_id "antmicropower:VCC_USR_A")
		(at 397.51 224.79 0)
		(mirror y)
		(unit 1)
		(exclude_from_sim no)
		(in_bom yes)
		(on_board yes)
		(dnp no)
		(fields_autoplaced yes)
		(property "Reference" "#PWR0429"
			(at 397.51 228.6 0)
			(effects
				(font
					(size 1.27 1.27)
				)
				(hide yes)
			)
		)
		(property "Value" "VCC_USR_A"
			(at 397.51 220.98 0)
			(effects
				(font
					(size 1.27 1.27)
				)
			)
		)
		(property "Footprint" ""
			(at 397.51 224.79 0)
			(effects
				(font
					(size 1.27 1.27)
				)
				(hide yes)
			)
		)
		(property "Datasheet" ""
			(at 397.51 224.79 0)
			(effects
				(font
					(size 1.27 1.27)
				)
				(hide yes)
			)
		)
		(property "Description" ""
			(at 397.51 224.79 0)
			(effects
				(font
					(size 1.27 1.27)
				)
			)
		)
		(pin "1"
		)
		(instances
			(project "k410t-devboard"
				(path ""
					(reference "#PWR0429")
					(unit 1)
				)
			)
		)
	)
	(symbol
		(lib_id "antmicroCapacitorsmisc:C_4u7_0201")
		(at 157.48 36.83 90)
		(unit 1)
		(exclude_from_sim no)
		(in_bom yes)
		(on_board yes)
		(dnp no)
		(property "Reference" "C57"
			(at 158.115 32.385 90)
			(effects
				(font
					(size 1.27 1.27)
				)
				(justify right)
			)
		)
		(property "Value" "C_4u7_0201"
			(at 167.64 16.51 0)
			(effects
				(font
					(size 1.27 1.27)
					(thickness 0.15)
				)
				(justify left bottom)
				(hide yes)
			)
		)
		(property "Footprint" "antmicro-footprints:C_0201"
			(at 170.18 16.51 0)
			(effects
				(font
					(size 1.27 1.27)
					(thickness 0.15)
				)
				(justify left bottom)
				(hide yes)
			)
		)
		(property "Datasheet" "https://www.murata.com/products/productdetail?partno=GRM035R60J475ME15%23"
			(at 172.72 16.51 0)
			(effects
				(font
					(size 1.27 1.27)
					(thickness 0.15)
				)
				(justify left bottom)
				(hide yes)
			)
		)
		(property "Description" ""
			(at 157.48 36.83 0)
			(effects
				(font
					(size 1.27 1.27)
				)
			)
		)
		(property "Manufacturer" "Murata"
			(at 177.8 16.51 0)
			(effects
				(font
					(size 1.27 1.27)
					(thickness 0.15)
				)
				(justify left bottom)
				(hide yes)
			)
		)
		(property "MPN" "GRM035R60J475ME15D"
			(at 175.26 16.51 0)
			(effects
				(font
					(size 1.27 1.27)
					(thickness 0.15)
				)
				(justify left bottom)
				(hide yes)
			)
		)
		(property "Val" "4u7"
			(at 158.115 36.195 90)
			(effects
				(font
					(size 1.27 1.27)
					(thickness 0.15)
				)
				(justify right)
			)
		)
		(property "License" "Apache-2.0"
			(at 180.34 16.51 0)
			(effects
				(font
					(size 1.27 1.27)
					(thickness 0.15)
				)
				(justify left bottom)
				(hide yes)
			)
		)
		(property "Author" "Antmicro"
			(at 182.88 16.51 0)
			(effects
				(font
					(size 1.27 1.27)
					(thickness 0.15)
				)
				(justify left bottom)
				(hide yes)
			)
		)
		(property "Voltage" ""
			(at 185.42 16.51 0)
			(effects
				(font
					(size 1.27 1.27)
				)
				(justify left bottom)
				(hide yes)
			)
		)
		(property "Dielectric" ""
			(at 187.96 16.51 0)
			(effects
				(font
					(size 1.27 1.27)
				)
				(justify left bottom)
				(hide yes)
			)
		)
		(pin "1"
		)
		(pin "2"
		)
		(instances
			(project "k410t-devboard"
				(path ""
					(reference "C57")
					(unit 1)
				)
			)
		)
	)
	(symbol
		(lib_id "antmicroCapacitorspol:C_Pol_330u_6.3V_KEMET-T520-B")
		(at 138.43 196.85 0)
		(mirror y)
		(unit 1)
		(exclude_from_sim no)
		(in_bom yes)
		(on_board yes)
		(dnp no)
		(property "Reference" "C1"
			(at 137.795 197.485 0)
			(effects
				(font
					(size 1.27 1.27)
				)
				(justify left)
			)
		)
		(property "Value" "C_Pol_330u_6.3V_KEMET-T520-B"
			(at 124.46 201.93 0)
			(effects
				(font
					(size 1.27 1.27)
					(thickness 0.15)
				)
				(justify left bottom)
				(hide yes)
			)
		)
		(property "Footprint" "antmicro-footprints:C_Pol_EIA-B"
			(at 124.46 204.47 0)
			(effects
				(font
					(size 1.27 1.27)
					(thickness 0.15)
				)
				(justify left bottom)
				(hide yes)
			)
		)
		(property "Datasheet" "https://content.kemet.com/datasheets/KEM_T2076_T52X-530.pdf"
			(at 124.46 207.01 0)
			(effects
				(font
					(size 1.27 1.27)
					(thickness 0.15)
				)
				(justify left bottom)
				(hide yes)
			)
		)
		(property "Description" ""
			(at 138.43 196.85 0)
			(effects
				(font
					(size 1.27 1.27)
				)
			)
		)
		(property "Manufacturer" "KEMET"
			(at 124.46 212.09 0)
			(effects
				(font
					(size 1.27 1.27)
					(thickness 0.15)
				)
				(justify left bottom)
				(hide yes)
			)
		)
		(property "MPN" "T520B337M006ATE040"
			(at 124.46 209.55 0)
			(effects
				(font
					(size 1.27 1.27)
					(thickness 0.15)
				)
				(justify left bottom)
				(hide yes)
			)
		)
		(property "Val" "330u"
			(at 137.795 201.93 0)
			(effects
				(font
					(size 1.27 1.27)
					(thickness 0.15)
				)
				(justify left)
			)
		)
		(property "License" "Apache-2.0"
			(at 124.46 214.63 0)
			(effects
				(font
					(size 1.27 1.27)
					(thickness 0.15)
				)
				(justify left bottom)
				(hide yes)
			)
		)
		(property "Author" "Antmicro"
			(at 124.46 217.17 0)
			(effects
				(font
					(size 1.27 1.27)
					(thickness 0.15)
				)
				(justify left bottom)
				(hide yes)
			)
		)
		(property "Voltage" "6.3V"
			(at 124.46 219.71 0)
			(effects
				(font
					(size 1.27 1.27)
				)
				(justify left bottom)
				(hide yes)
			)
		)
		(property "Dielectric" ""
			(at 124.46 222.25 0)
			(effects
				(font
					(size 1.27 1.27)
				)
				(justify left bottom)
				(hide yes)
			)
		)
		(pin "1"
		)
		(pin "2"
		)
		(instances
			(project "k410t-devboard"
				(path ""
					(reference "C1")
					(unit 1)
				)
			)
		)
	)
	(symbol
		(lib_id "antmicroCapacitorsmisc:C_100n_0201")
		(at 195.58 76.2 90)
		(unit 1)
		(exclude_from_sim no)
		(in_bom yes)
		(on_board yes)
		(dnp no)
		(property "Reference" "C150"
			(at 196.215 71.755 90)
			(effects
				(font
					(size 1.27 1.27)
				)
				(justify right)
			)
		)
		(property "Value" "C_100n_0201"
			(at 205.74 55.88 0)
			(effects
				(font
					(size 1.27 1.27)
					(thickness 0.15)
				)
				(justify left bottom)
				(hide yes)
			)
		)
		(property "Footprint" "antmicro-footprints:C_0201"
			(at 208.28 55.88 0)
			(effects
				(font
					(size 1.27 1.27)
					(thickness 0.15)
				)
				(justify left bottom)
				(hide yes)
			)
		)
		(property "Datasheet" "https://www.yageo.com/en/Chart/Download/pdf/CC0201KRX6S5BB104"
			(at 210.82 55.88 0)
			(effects
				(font
					(size 1.27 1.27)
					(thickness 0.15)
				)
				(justify left bottom)
				(hide yes)
			)
		)
		(property "Description" ""
			(at 195.58 76.2 0)
			(effects
				(font
					(size 1.27 1.27)
				)
			)
		)
		(property "Manufacturer" "YAGEO"
			(at 215.9 55.88 0)
			(effects
				(font
					(size 1.27 1.27)
					(thickness 0.15)
				)
				(justify left bottom)
				(hide yes)
			)
		)
		(property "MPN" "CC0201KRX6S5BB104"
			(at 213.36 55.88 0)
			(effects
				(font
					(size 1.27 1.27)
					(thickness 0.15)
				)
				(justify left bottom)
				(hide yes)
			)
		)
		(property "Val" "100n"
			(at 196.215 75.565 90)
			(effects
				(font
					(size 1.27 1.27)
					(thickness 0.15)
				)
				(justify right)
			)
		)
		(property "License" "Apache-2.0"
			(at 218.44 55.88 0)
			(effects
				(font
					(size 1.27 1.27)
					(thickness 0.15)
				)
				(justify left bottom)
				(hide yes)
			)
		)
		(property "Author" "Antmicro"
			(at 220.98 55.88 0)
			(effects
				(font
					(size 1.27 1.27)
					(thickness 0.15)
				)
				(justify left bottom)
				(hide yes)
			)
		)
		(property "Voltage" ""
			(at 223.52 55.88 0)
			(effects
				(font
					(size 1.27 1.27)
				)
				(justify left bottom)
				(hide yes)
			)
		)
		(property "Dielectric" ""
			(at 226.06 55.88 0)
			(effects
				(font
					(size 1.27 1.27)
				)
				(justify left bottom)
				(hide yes)
			)
		)
		(pin "1"
		)
		(pin "2"
		)
		(instances
			(project "k410t-devboard"
				(path ""
					(reference "C150")
					(unit 1)
				)
			)
		)
	)
	(symbol
		(lib_id "antmicroCapacitors0603:C_47u_0603")
		(at 146.05 238.76 270)
		(mirror x)
		(unit 1)
		(exclude_from_sim no)
		(in_bom yes)
		(on_board yes)
		(dnp no)
		(property "Reference" "C384"
			(at 145.415 234.315 90)
			(effects
				(font
					(size 1.27 1.27)
				)
				(justify right)
			)
		)
		(property "Value" "C_47u_0603"
			(at 135.89 218.44 0)
			(effects
				(font
					(size 1.27 1.27)
					(thickness 0.15)
				)
				(justify left bottom)
				(hide yes)
			)
		)
		(property "Footprint" "antmicro-footprints:C_0603_1608Metric"
			(at 133.35 218.44 0)
			(effects
				(font
					(size 1.27 1.27)
					(thickness 0.15)
				)
				(justify left bottom)
				(hide yes)
			)
		)
		(property "Datasheet" "https://www.murata.com/products/productdetail?partno=GRM188R60J476ME15%23"
			(at 130.81 218.44 0)
			(effects
				(font
					(size 1.27 1.27)
					(thickness 0.15)
				)
				(justify left bottom)
				(hide yes)
			)
		)
		(property "Description" ""
			(at 146.05 238.76 0)
			(effects
				(font
					(size 1.27 1.27)
				)
			)
		)
		(property "Manufacturer" "Murata"
			(at 125.73 218.44 0)
			(effects
				(font
					(size 1.27 1.27)
					(thickness 0.15)
				)
				(justify left bottom)
				(hide yes)
			)
		)
		(property "MPN" "GRM188R60J476ME15D"
			(at 128.27 218.44 0)
			(effects
				(font
					(size 1.27 1.27)
					(thickness 0.15)
				)
				(justify left bottom)
				(hide yes)
			)
		)
		(property "Val" "47u"
			(at 145.415 238.125 90)
			(effects
				(font
					(size 1.27 1.27)
					(thickness 0.15)
				)
				(justify right)
			)
		)
		(property "License" "Apache-2.0"
			(at 123.19 218.44 0)
			(effects
				(font
					(size 1.27 1.27)
					(thickness 0.15)
				)
				(justify left bottom)
				(hide yes)
			)
		)
		(property "Author" "Antmicro"
			(at 120.65 218.44 0)
			(effects
				(font
					(size 1.27 1.27)
					(thickness 0.15)
				)
				(justify left bottom)
				(hide yes)
			)
		)
		(property "Voltage" ""
			(at 118.11 218.44 0)
			(effects
				(font
					(size 1.27 1.27)
				)
				(justify left bottom)
				(hide yes)
			)
		)
		(property "Dielectric" ""
			(at 115.57 218.44 0)
			(effects
				(font
					(size 1.27 1.27)
				)
				(justify left bottom)
				(hide yes)
			)
		)
		(pin "1"
		)
		(pin "2"
		)
		(instances
			(project "k410t-devboard"
				(path ""
					(reference "C384")
					(unit 1)
				)
			)
		)
	)
	(symbol
		(lib_id "antmicropower:+1V2_MGTAVTT")
		(at 139.7 85.09 0)
		(unit 1)
		(exclude_from_sim no)
		(in_bom yes)
		(on_board yes)
		(dnp no)
		(property "Reference" "#PWR041"
			(at 139.7 88.9 0)
			(effects
				(font
					(size 1.27 1.27)
				)
				(hide yes)
			)
		)
		(property "Value" "+1V2_MGTAVTT"
			(at 139.7 81.28 0)
			(effects
				(font
					(size 1.27 1.27)
				)
			)
		)
		(property "Footprint" ""
			(at 139.7 85.09 0)
			(effects
				(font
					(size 1.27 1.27)
				)
				(hide yes)
			)
		)
		(property "Datasheet" ""
			(at 139.7 85.09 0)
			(effects
				(font
					(size 1.27 1.27)
				)
				(hide yes)
			)
		)
		(property "Description" ""
			(at 139.7 85.09 0)
			(effects
				(font
					(size 1.27 1.27)
				)
			)
		)
		(pin "1"
		)
		(instances
			(project "k410t-devboard"
				(path ""
					(reference "#PWR041")
					(unit 1)
				)
			)
		)
	)
	(symbol
		(lib_id "antmicropower:+1V85_ADC")
		(at 229.87 177.8 0)
		(unit 1)
		(exclude_from_sim no)
		(in_bom yes)
		(on_board yes)
		(dnp no)
		(fields_autoplaced yes)
		(property "Reference" "#PWR019"
			(at 229.87 181.61 0)
			(effects
				(font
					(size 1.27 1.27)
				)
				(hide yes)
			)
		)
		(property "Value" "+1V85_ADC"
			(at 229.87 174.244 0)
			(effects
				(font
					(size 1.27 1.27)
				)
			)
		)
		(property "Footprint" ""
			(at 229.87 177.8 0)
			(effects
				(font
					(size 1.27 1.27)
				)
				(hide yes)
			)
		)
		(property "Datasheet" ""
			(at 229.87 177.8 0)
			(effects
				(font
					(size 1.27 1.27)
				)
				(hide yes)
			)
		)
		(property "Description" ""
			(at 229.87 177.8 0)
			(effects
				(font
					(size 1.27 1.27)
				)
			)
		)
		(pin "1"
		)
		(instances
			(project "k410t-devboard"
				(path ""
					(reference "#PWR019")
					(unit 1)
				)
			)
		)
	)
	(symbol
		(lib_id "antmicroCapacitors0603:C_47u_0603")
		(at 165.1 93.98 90)
		(unit 1)
		(exclude_from_sim no)
		(in_bom yes)
		(on_board yes)
		(dnp no)
		(property "Reference" "C120"
			(at 165.735 89.535 90)
			(effects
				(font
					(size 1.27 1.27)
				)
				(justify right)
			)
		)
		(property "Value" "C_47u_0603"
			(at 175.26 73.66 0)
			(effects
				(font
					(size 1.27 1.27)
					(thickness 0.15)
				)
				(justify left bottom)
				(hide yes)
			)
		)
		(property "Footprint" "antmicro-footprints:C_0603_1608Metric"
			(at 177.8 73.66 0)
			(effects
				(font
					(size 1.27 1.27)
					(thickness 0.15)
				)
				(justify left bottom)
				(hide yes)
			)
		)
		(property "Datasheet" "https://www.murata.com/products/productdetail?partno=GRM188R60J476ME15%23"
			(at 180.34 73.66 0)
			(effects
				(font
					(size 1.27 1.27)
					(thickness 0.15)
				)
				(justify left bottom)
				(hide yes)
			)
		)
		(property "Description" ""
			(at 165.1 93.98 0)
			(effects
				(font
					(size 1.27 1.27)
				)
			)
		)
		(property "Manufacturer" "Murata"
			(at 185.42 73.66 0)
			(effects
				(font
					(size 1.27 1.27)
					(thickness 0.15)
				)
				(justify left bottom)
				(hide yes)
			)
		)
		(property "MPN" "GRM188R60J476ME15D"
			(at 182.88 73.66 0)
			(effects
				(font
					(size 1.27 1.27)
					(thickness 0.15)
				)
				(justify left bottom)
				(hide yes)
			)
		)
		(property "Val" "47u"
			(at 165.735 93.345 90)
			(effects
				(font
					(size 1.27 1.27)
					(thickness 0.15)
				)
				(justify right)
			)
		)
		(property "License" "Apache-2.0"
			(at 187.96 73.66 0)
			(effects
				(font
					(size 1.27 1.27)
					(thickness 0.15)
				)
				(justify left bottom)
				(hide yes)
			)
		)
		(property "Author" "Antmicro"
			(at 190.5 73.66 0)
			(effects
				(font
					(size 1.27 1.27)
					(thickness 0.15)
				)
				(justify left bottom)
				(hide yes)
			)
		)
		(property "Voltage" ""
			(at 193.04 73.66 0)
			(effects
				(font
					(size 1.27 1.27)
				)
				(justify left bottom)
				(hide yes)
			)
		)
		(property "Dielectric" ""
			(at 195.58 73.66 0)
			(effects
				(font
					(size 1.27 1.27)
				)
				(justify left bottom)
				(hide yes)
			)
		)
		(pin "1"
		)
		(pin "2"
		)
		(instances
			(project "k410t-devboard"
				(path ""
					(reference "C120")
					(unit 1)
				)
			)
		)
	)
	(symbol
		(lib_id "antmicroCapacitors0603:C_47u_0603")
		(at 161.29 238.76 270)
		(mirror x)
		(unit 1)
		(exclude_from_sim no)
		(in_bom yes)
		(on_board yes)
		(dnp no)
		(property "Reference" "C382"
			(at 160.655 234.315 90)
			(effects
				(font
					(size 1.27 1.27)
				)
				(justify right)
			)
		)
		(property "Value" "C_47u_0603"
			(at 151.13 218.44 0)
			(effects
				(font
					(size 1.27 1.27)
					(thickness 0.15)
				)
				(justify left bottom)
				(hide yes)
			)
		)
		(property "Footprint" "antmicro-footprints:C_0603_1608Metric"
			(at 148.59 218.44 0)
			(effects
				(font
					(size 1.27 1.27)
					(thickness 0.15)
				)
				(justify left bottom)
				(hide yes)
			)
		)
		(property "Datasheet" "https://www.murata.com/products/productdetail?partno=GRM188R60J476ME15%23"
			(at 146.05 218.44 0)
			(effects
				(font
					(size 1.27 1.27)
					(thickness 0.15)
				)
				(justify left bottom)
				(hide yes)
			)
		)
		(property "Description" ""
			(at 161.29 238.76 0)
			(effects
				(font
					(size 1.27 1.27)
				)
			)
		)
		(property "Manufacturer" "Murata"
			(at 140.97 218.44 0)
			(effects
				(font
					(size 1.27 1.27)
					(thickness 0.15)
				)
				(justify left bottom)
				(hide yes)
			)
		)
		(property "MPN" "GRM188R60J476ME15D"
			(at 143.51 218.44 0)
			(effects
				(font
					(size 1.27 1.27)
					(thickness 0.15)
				)
				(justify left bottom)
				(hide yes)
			)
		)
		(property "Val" "47u"
			(at 160.655 238.125 90)
			(effects
				(font
					(size 1.27 1.27)
					(thickness 0.15)
				)
				(justify right)
			)
		)
		(property "License" "Apache-2.0"
			(at 138.43 218.44 0)
			(effects
				(font
					(size 1.27 1.27)
					(thickness 0.15)
				)
				(justify left bottom)
				(hide yes)
			)
		)
		(property "Author" "Antmicro"
			(at 135.89 218.44 0)
			(effects
				(font
					(size 1.27 1.27)
					(thickness 0.15)
				)
				(justify left bottom)
				(hide yes)
			)
		)
		(property "Voltage" ""
			(at 133.35 218.44 0)
			(effects
				(font
					(size 1.27 1.27)
				)
				(justify left bottom)
				(hide yes)
			)
		)
		(property "Dielectric" ""
			(at 130.81 218.44 0)
			(effects
				(font
					(size 1.27 1.27)
				)
				(justify left bottom)
				(hide yes)
			)
		)
		(pin "1"
		)
		(pin "2"
		)
		(instances
			(project "k410t-devboard"
				(path ""
					(reference "C382")
					(unit 1)
				)
			)
		)
	)
	(symbol
		(lib_id "antmicroCapacitors0603:C_47u_0603")
		(at 138.43 220.98 270)
		(mirror x)
		(unit 1)
		(exclude_from_sim no)
		(in_bom yes)
		(on_board yes)
		(dnp no)
		(property "Reference" "C379"
			(at 137.795 216.535 90)
			(effects
				(font
					(size 1.27 1.27)
				)
				(justify right)
			)
		)
		(property "Value" "C_47u_0603"
			(at 128.27 200.66 0)
			(effects
				(font
					(size 1.27 1.27)
					(thickness 0.15)
				)
				(justify left bottom)
				(hide yes)
			)
		)
		(property "Footprint" "antmicro-footprints:C_0603_1608Metric"
			(at 125.73 200.66 0)
			(effects
				(font
					(size 1.27 1.27)
					(thickness 0.15)
				)
				(justify left bottom)
				(hide yes)
			)
		)
		(property "Datasheet" "https://www.murata.com/products/productdetail?partno=GRM188R60J476ME15%23"
			(at 123.19 200.66 0)
			(effects
				(font
					(size 1.27 1.27)
					(thickness 0.15)
				)
				(justify left bottom)
				(hide yes)
			)
		)
		(property "Description" ""
			(at 138.43 220.98 0)
			(effects
				(font
					(size 1.27 1.27)
				)
			)
		)
		(property "Manufacturer" "Murata"
			(at 118.11 200.66 0)
			(effects
				(font
					(size 1.27 1.27)
					(thickness 0.15)
				)
				(justify left bottom)
				(hide yes)
			)
		)
		(property "MPN" "GRM188R60J476ME15D"
			(at 120.65 200.66 0)
			(effects
				(font
					(size 1.27 1.27)
					(thickness 0.15)
				)
				(justify left bottom)
				(hide yes)
			)
		)
		(property "Val" "47u"
			(at 137.795 220.345 90)
			(effects
				(font
					(size 1.27 1.27)
					(thickness 0.15)
				)
				(justify right)
			)
		)
		(property "License" "Apache-2.0"
			(at 115.57 200.66 0)
			(effects
				(font
					(size 1.27 1.27)
					(thickness 0.15)
				)
				(justify left bottom)
				(hide yes)
			)
		)
		(property "Author" "Antmicro"
			(at 113.03 200.66 0)
			(effects
				(font
					(size 1.27 1.27)
					(thickness 0.15)
				)
				(justify left bottom)
				(hide yes)
			)
		)
		(property "Voltage" ""
			(at 110.49 200.66 0)
			(effects
				(font
					(size 1.27 1.27)
				)
				(justify left bottom)
				(hide yes)
			)
		)
		(property "Dielectric" ""
			(at 107.95 200.66 0)
			(effects
				(font
					(size 1.27 1.27)
				)
				(justify left bottom)
				(hide yes)
			)
		)
		(pin "1"
		)
		(pin "2"
		)
		(instances
			(project "k410t-devboard"
				(path ""
					(reference "C379")
					(unit 1)
				)
			)
		)
	)
	(symbol
		(lib_id "antmicroCapacitorsmisc:C_4u7_0201")
		(at 149.86 76.2 90)
		(unit 1)
		(exclude_from_sim no)
		(in_bom yes)
		(on_board yes)
		(dnp no)
		(property "Reference" "C160"
			(at 150.495 71.755 90)
			(effects
				(font
					(size 1.27 1.27)
				)
				(justify right)
			)
		)
		(property "Value" "C_4u7_0201"
			(at 160.02 55.88 0)
			(effects
				(font
					(size 1.27 1.27)
					(thickness 0.15)
				)
				(justify left bottom)
				(hide yes)
			)
		)
		(property "Footprint" "antmicro-footprints:C_0201"
			(at 162.56 55.88 0)
			(effects
				(font
					(size 1.27 1.27)
					(thickness 0.15)
				)
				(justify left bottom)
				(hide yes)
			)
		)
		(property "Datasheet" "https://www.murata.com/products/productdetail?partno=GRM035R60J475ME15%23"
			(at 165.1 55.88 0)
			(effects
				(font
					(size 1.27 1.27)
					(thickness 0.15)
				)
				(justify left bottom)
				(hide yes)
			)
		)
		(property "Description" ""
			(at 149.86 76.2 0)
			(effects
				(font
					(size 1.27 1.27)
				)
			)
		)
		(property "Manufacturer" "Murata"
			(at 170.18 55.88 0)
			(effects
				(font
					(size 1.27 1.27)
					(thickness 0.15)
				)
				(justify left bottom)
				(hide yes)
			)
		)
		(property "MPN" "GRM035R60J475ME15D"
			(at 167.64 55.88 0)
			(effects
				(font
					(size 1.27 1.27)
					(thickness 0.15)
				)
				(justify left bottom)
				(hide yes)
			)
		)
		(property "Val" "4u7"
			(at 150.495 75.565 90)
			(effects
				(font
					(size 1.27 1.27)
					(thickness 0.15)
				)
				(justify right)
			)
		)
		(property "License" "Apache-2.0"
			(at 172.72 55.88 0)
			(effects
				(font
					(size 1.27 1.27)
					(thickness 0.15)
				)
				(justify left bottom)
				(hide yes)
			)
		)
		(property "Author" "Antmicro"
			(at 175.26 55.88 0)
			(effects
				(font
					(size 1.27 1.27)
					(thickness 0.15)
				)
				(justify left bottom)
				(hide yes)
			)
		)
		(property "Voltage" ""
			(at 177.8 55.88 0)
			(effects
				(font
					(size 1.27 1.27)
				)
				(justify left bottom)
				(hide yes)
			)
		)
		(property "Dielectric" ""
			(at 180.34 55.88 0)
			(effects
				(font
					(size 1.27 1.27)
				)
				(justify left bottom)
				(hide yes)
			)
		)
		(pin "1"
		)
		(pin "2"
		)
		(instances
			(project "k410t-devboard"
				(path ""
					(reference "C160")
					(unit 1)
				)
			)
		)
	)
	(symbol
		(lib_id "antmicroCapacitors0402:C_100n_0402")
		(at 237.49 220.98 270)
		(mirror x)
		(unit 1)
		(exclude_from_sim no)
		(in_bom yes)
		(on_board yes)
		(dnp no)
		(property "Reference" "C114"
			(at 236.855 216.535 90)
			(effects
				(font
					(size 1.27 1.27)
				)
				(justify right)
			)
		)
		(property "Value" "C_100n_0402"
			(at 227.33 200.66 0)
			(effects
				(font
					(size 1.27 1.27)
					(thickness 0.15)
				)
				(justify left bottom)
				(hide yes)
			)
		)
		(property "Footprint" "antmicro-footprints:C_0402_1005Metric"
			(at 224.79 200.66 0)
			(effects
				(font
					(size 1.27 1.27)
					(thickness 0.15)
				)
				(justify left bottom)
				(hide yes)
			)
		)
		(property "Datasheet" "https://www.murata.com/products/productdetail?partno=GRM155R61H104KE14%23"
			(at 222.25 200.66 0)
			(effects
				(font
					(size 1.27 1.27)
					(thickness 0.15)
				)
				(justify left bottom)
				(hide yes)
			)
		)
		(property "Description" ""
			(at 237.49 220.98 0)
			(effects
				(font
					(size 1.27 1.27)
				)
			)
		)
		(property "Manufacturer" "Murata"
			(at 217.17 200.66 0)
			(effects
				(font
					(size 1.27 1.27)
					(thickness 0.15)
				)
				(justify left bottom)
				(hide yes)
			)
		)
		(property "MPN" "GRM155R61H104KE14D"
			(at 219.71 200.66 0)
			(effects
				(font
					(size 1.27 1.27)
					(thickness 0.15)
				)
				(justify left bottom)
				(hide yes)
			)
		)
		(property "Val" "100n"
			(at 236.855 220.345 90)
			(effects
				(font
					(size 1.27 1.27)
					(thickness 0.15)
				)
				(justify right)
			)
		)
		(property "License" "Apache-2.0"
			(at 214.63 200.66 0)
			(effects
				(font
					(size 1.27 1.27)
					(thickness 0.15)
				)
				(justify left bottom)
				(hide yes)
			)
		)
		(property "Author" "Antmicro"
			(at 212.09 200.66 0)
			(effects
				(font
					(size 1.27 1.27)
					(thickness 0.15)
				)
				(justify left bottom)
				(hide yes)
			)
		)
		(property "Voltage" "50V"
			(at 209.55 200.66 0)
			(effects
				(font
					(size 1.27 1.27)
				)
				(justify left bottom)
				(hide yes)
			)
		)
		(property "Dielectric" "X5R"
			(at 207.01 200.66 0)
			(effects
				(font
					(size 1.27 1.27)
				)
				(justify left bottom)
				(hide yes)
			)
		)
		(pin "1"
		)
		(pin "2"
		)
		(instances
			(project "k410t-devboard"
				(path ""
					(reference "C114")
					(unit 1)
				)
			)
		)
	)
	(symbol
		(lib_id "antmicropower:+1V8")
		(at 184.15 142.24 0)
		(unit 1)
		(exclude_from_sim no)
		(in_bom yes)
		(on_board yes)
		(dnp no)
		(fields_autoplaced yes)
		(property "Reference" "#PWR013"
			(at 184.15 146.05 0)
			(effects
				(font
					(size 1.27 1.27)
				)
				(hide yes)
			)
		)
		(property "Value" "+1V8"
			(at 184.15 138.684 0)
			(effects
				(font
					(size 1.27 1.27)
				)
			)
		)
		(property "Footprint" ""
			(at 199.39 149.86 0)
			(effects
				(font
					(size 1.27 1.27)
					(thickness 0.15)
				)
				(justify left bottom)
				(hide yes)
			)
		)
		(property "Datasheet" ""
			(at 199.39 152.4 0)
			(effects
				(font
					(size 1.27 1.27)
					(thickness 0.15)
				)
				(justify left bottom)
				(hide yes)
			)
		)
		(property "Description" ""
			(at 184.15 142.24 0)
			(effects
				(font
					(size 1.27 1.27)
				)
			)
		)
		(property "Author" "Antmicro"
			(at 199.39 149.86 0)
			(effects
				(font
					(size 1.27 1.27)
					(thickness 0.15)
				)
				(justify left bottom)
				(hide yes)
			)
		)
		(property "License" "Apache-2.0"
			(at 199.39 152.4 0)
			(effects
				(font
					(size 1.27 1.27)
					(thickness 0.15)
				)
				(justify left bottom)
				(hide yes)
			)
		)
		(pin "1"
		)
		(instances
			(project "k410t-devboard"
				(path ""
					(reference "#PWR013")
					(unit 1)
				)
			)
		)
	)
	(symbol
		(lib_id "antmicroCapacitors0402:C_100n_0402")
		(at 227.33 48.26 270)
		(unit 1)
		(exclude_from_sim no)
		(in_bom yes)
		(on_board yes)
		(dnp no)
		(property "Reference" "C118"
			(at 226.695 48.895 90)
			(effects
				(font
					(size 1.27 1.27)
				)
				(justify right)
			)
		)
		(property "Value" "C_100n_0402"
			(at 217.17 68.58 0)
			(effects
				(font
					(size 1.27 1.27)
					(thickness 0.15)
				)
				(justify left bottom)
				(hide yes)
			)
		)
		(property "Footprint" "antmicro-footprints:C_0402_1005Metric"
			(at 214.63 68.58 0)
			(effects
				(font
					(size 1.27 1.27)
					(thickness 0.15)
				)
				(justify left bottom)
				(hide yes)
			)
		)
		(property "Datasheet" "https://www.murata.com/products/productdetail?partno=GRM155R61H104KE14%23"
			(at 212.09 68.58 0)
			(effects
				(font
					(size 1.27 1.27)
					(thickness 0.15)
				)
				(justify left bottom)
				(hide yes)
			)
		)
		(property "Description" ""
			(at 227.33 48.26 0)
			(effects
				(font
					(size 1.27 1.27)
				)
			)
		)
		(property "Manufacturer" "Murata"
			(at 207.01 68.58 0)
			(effects
				(font
					(size 1.27 1.27)
					(thickness 0.15)
				)
				(justify left bottom)
				(hide yes)
			)
		)
		(property "MPN" "GRM155R61H104KE14D"
			(at 209.55 68.58 0)
			(effects
				(font
					(size 1.27 1.27)
					(thickness 0.15)
				)
				(justify left bottom)
				(hide yes)
			)
		)
		(property "Val" "100n"
			(at 226.695 52.705 90)
			(effects
				(font
					(size 1.27 1.27)
					(thickness 0.15)
				)
				(justify right)
			)
		)
		(property "License" "Apache-2.0"
			(at 204.47 68.58 0)
			(effects
				(font
					(size 1.27 1.27)
					(thickness 0.15)
				)
				(justify left bottom)
				(hide yes)
			)
		)
		(property "Author" "Antmicro"
			(at 201.93 68.58 0)
			(effects
				(font
					(size 1.27 1.27)
					(thickness 0.15)
				)
				(justify left bottom)
				(hide yes)
			)
		)
		(property "Voltage" "50V"
			(at 199.39 68.58 0)
			(effects
				(font
					(size 1.27 1.27)
				)
				(justify left bottom)
				(hide yes)
			)
		)
		(property "Dielectric" "X5R"
			(at 196.85 68.58 0)
			(effects
				(font
					(size 1.27 1.27)
				)
				(justify left bottom)
				(hide yes)
			)
		)
		(pin "1"
		)
		(pin "2"
		)
		(instances
			(project "k410t-devboard"
				(path ""
					(reference "C118")
					(unit 1)
				)
			)
		)
	)
	(symbol
		(lib_id "antmicroCapacitorsmisc:C_100n_0201")
		(at 226.06 93.98 90)
		(unit 1)
		(exclude_from_sim no)
		(in_bom yes)
		(on_board yes)
		(dnp no)
		(property "Reference" "C157"
			(at 226.695 89.535 90)
			(effects
				(font
					(size 1.27 1.27)
				)
				(justify right)
			)
		)
		(property "Value" "C_100n_0201"
			(at 236.22 73.66 0)
			(effects
				(font
					(size 1.27 1.27)
					(thickness 0.15)
				)
				(justify left bottom)
				(hide yes)
			)
		)
		(property "Footprint" "antmicro-footprints:C_0201"
			(at 238.76 73.66 0)
			(effects
				(font
					(size 1.27 1.27)
					(thickness 0.15)
				)
				(justify left bottom)
				(hide yes)
			)
		)
		(property "Datasheet" "https://www.yageo.com/en/Chart/Download/pdf/CC0201KRX6S5BB104"
			(at 241.3 73.66 0)
			(effects
				(font
					(size 1.27 1.27)
					(thickness 0.15)
				)
				(justify left bottom)
				(hide yes)
			)
		)
		(property "Description" ""
			(at 226.06 93.98 0)
			(effects
				(font
					(size 1.27 1.27)
				)
			)
		)
		(property "Manufacturer" "YAGEO"
			(at 246.38 73.66 0)
			(effects
				(font
					(size 1.27 1.27)
					(thickness 0.15)
				)
				(justify left bottom)
				(hide yes)
			)
		)
		(property "MPN" "CC0201KRX6S5BB104"
			(at 243.84 73.66 0)
			(effects
				(font
					(size 1.27 1.27)
					(thickness 0.15)
				)
				(justify left bottom)
				(hide yes)
			)
		)
		(property "Val" "100n"
			(at 226.695 93.345 90)
			(effects
				(font
					(size 1.27 1.27)
					(thickness 0.15)
				)
				(justify right)
			)
		)
		(property "License" "Apache-2.0"
			(at 248.92 73.66 0)
			(effects
				(font
					(size 1.27 1.27)
					(thickness 0.15)
				)
				(justify left bottom)
				(hide yes)
			)
		)
		(property "Author" "Antmicro"
			(at 251.46 73.66 0)
			(effects
				(font
					(size 1.27 1.27)
					(thickness 0.15)
				)
				(justify left bottom)
				(hide yes)
			)
		)
		(property "Voltage" ""
			(at 254 73.66 0)
			(effects
				(font
					(size 1.27 1.27)
				)
				(justify left bottom)
				(hide yes)
			)
		)
		(property "Dielectric" ""
			(at 256.54 73.66 0)
			(effects
				(font
					(size 1.27 1.27)
				)
				(justify left bottom)
				(hide yes)
			)
		)
		(pin "1"
		)
		(pin "2"
		)
		(instances
			(project "k410t-devboard"
				(path ""
					(reference "C157")
					(unit 1)
				)
			)
		)
	)
	(symbol
		(lib_id "antmicroCapacitors0603:C_47u_0603")
		(at 123.19 220.98 270)
		(mirror x)
		(unit 1)
		(exclude_from_sim no)
		(in_bom yes)
		(on_board yes)
		(dnp no)
		(property "Reference" "C381"
			(at 122.555 216.535 90)
			(effects
				(font
					(size 1.27 1.27)
				)
				(justify right)
			)
		)
		(property "Value" "C_47u_0603"
			(at 113.03 200.66 0)
			(effects
				(font
					(size 1.27 1.27)
					(thickness 0.15)
				)
				(justify left bottom)
				(hide yes)
			)
		)
		(property "Footprint" "antmicro-footprints:C_0603_1608Metric"
			(at 110.49 200.66 0)
			(effects
				(font
					(size 1.27 1.27)
					(thickness 0.15)
				)
				(justify left bottom)
				(hide yes)
			)
		)
		(property "Datasheet" "https://www.murata.com/products/productdetail?partno=GRM188R60J476ME15%23"
			(at 107.95 200.66 0)
			(effects
				(font
					(size 1.27 1.27)
					(thickness 0.15)
				)
				(justify left bottom)
				(hide yes)
			)
		)
		(property "Description" ""
			(at 123.19 220.98 0)
			(effects
				(font
					(size 1.27 1.27)
				)
			)
		)
		(property "Manufacturer" "Murata"
			(at 102.87 200.66 0)
			(effects
				(font
					(size 1.27 1.27)
					(thickness 0.15)
				)
				(justify left bottom)
				(hide yes)
			)
		)
		(property "MPN" "GRM188R60J476ME15D"
			(at 105.41 200.66 0)
			(effects
				(font
					(size 1.27 1.27)
					(thickness 0.15)
				)
				(justify left bottom)
				(hide yes)
			)
		)
		(property "Val" "47u"
			(at 122.555 220.345 90)
			(effects
				(font
					(size 1.27 1.27)
					(thickness 0.15)
				)
				(justify right)
			)
		)
		(property "License" "Apache-2.0"
			(at 100.33 200.66 0)
			(effects
				(font
					(size 1.27 1.27)
					(thickness 0.15)
				)
				(justify left bottom)
				(hide yes)
			)
		)
		(property "Author" "Antmicro"
			(at 97.79 200.66 0)
			(effects
				(font
					(size 1.27 1.27)
					(thickness 0.15)
				)
				(justify left bottom)
				(hide yes)
			)
		)
		(property "Voltage" ""
			(at 95.25 200.66 0)
			(effects
				(font
					(size 1.27 1.27)
				)
				(justify left bottom)
				(hide yes)
			)
		)
		(property "Dielectric" ""
			(at 92.71 200.66 0)
			(effects
				(font
					(size 1.27 1.27)
				)
				(justify left bottom)
				(hide yes)
			)
		)
		(pin "1"
		)
		(pin "2"
		)
		(instances
			(project "k410t-devboard"
				(path ""
					(reference "C381")
					(unit 1)
				)
			)
		)
	)
	(symbol
		(lib_name "XC7K410T-2FFG900I_3")
		(lib_id "antmicroFPGAChips:XC7K410T-2FFG900I")
		(at 248.92 59.69 0)
		(unit 8)
		(exclude_from_sim no)
		(in_bom yes)
		(on_board yes)
		(dnp no)
		(fields_autoplaced yes)
		(property "Reference" "U1"
			(at 274.32 64.135 0)
			(effects
				(font
					(size 1.27 1.27)
					(thickness 0.15)
				)
				(justify left)
			)
		)
		(property "Value" "XC7K410T-2FFG900I"
			(at 274.32 66.675 0)
			(effects
				(font
					(size 1.27 1.27)
					(thickness 0.15)
				)
				(justify left)
			)
		)
		(property "Footprint" "antmicro-footprints:BGA-900_31x31mm_Layout30x30_P1x1mm_FFG900"
			(at 248.92 33.02 0)
			(effects
				(font
					(size 1.27 1.27)
					(thickness 0.15)
				)
				(justify left bottom)
				(hide yes)
			)
		)
		(property "Datasheet" "https://eu.mouser.com/datasheet/2/903/ds180_7Series_Overview-1591537.pdf"
			(at 248.92 35.56 0)
			(effects
				(font
					(size 1.27 1.27)
					(thickness 0.15)
				)
				(justify left bottom)
				(hide yes)
			)
		)
		(property "Description" ""
			(at 248.92 59.69 0)
			(effects
				(font
					(size 1.27 1.27)
				)
			)
		)
		(property "Manufacturer" "AMD-Xilinx"
			(at 248.92 38.1 0)
			(effects
				(font
					(size 1.27 1.27)
					(thickness 0.15)
				)
				(justify left bottom)
				(hide yes)
			)
		)
		(property "MPN" "XC7K410T-2FFG900I"
			(at 248.92 40.64 0)
			(effects
				(font
					(size 1.27 1.27)
					(thickness 0.15)
				)
				(justify left bottom)
				(hide yes)
			)
		)
		(property "Author" "Antmicro"
			(at 248.92 43.18 0)
			(effects
				(font
					(size 1.27 1.27)
					(thickness 0.15)
				)
				(justify left bottom)
				(hide yes)
			)
		)
		(property "License" "Apache-2.0"
			(at 248.92 45.72 0)
			(effects
				(font
					(size 1.27 1.27)
					(thickness 0.15)
				)
				(justify left bottom)
				(hide yes)
			)
		)
		(pin "B3"
		)
		(pin "B7"
		)
		(pin "C5"
		)
		(pin "D3"
		)
		(pin "D7"
		)
		(pin "E5"
		)
		(pin "F3"
		)
		(pin "F7"
		)
		(pin "G5"
		)
		(pin "H3"
		)
		(pin "H7"
		)
		(pin "J5"
		)
		(pin "K3"
		)
		(pin "K7"
		)
		(pin "L5"
		)
		(pin "M3"
		)
		(pin "M7"
		)
		(pin "N5"
		)
		(pin "P3"
		)
		(pin "P7"
		)
		(pin "R5"
		)
		(pin "T3"
		)
		(pin "T7"
		)
		(pin "U5"
		)
		(pin "V3"
		)
		(pin "V7"
		)
		(pin "W5"
		)
		(pin "W7"
		)
		(pin "W8"
		)
		(pin "AA20"
		)
		(pin "AA21"
		)
		(pin "AA22"
		)
		(pin "AA23"
		)
		(pin "AB20"
		)
		(pin "AB22"
		)
		(pin "AB23"
		)
		(pin "AB24"
		)
		(pin "AC20"
		)
		(pin "AC21"
		)
		(pin "AC22"
		)
		(pin "AC24"
		)
		(pin "AC25"
		)
		(pin "AD21"
		)
		(pin "AD22"
		)
		(pin "AD23"
		)
		(pin "AD24"
		)
		(pin "AE20"
		)
		(pin "AE21"
		)
		(pin "AE23"
		)
		(pin "AE24"
		)
		(pin "AE25"
		)
		(pin "AF20"
		)
		(pin "AF21"
		)
		(pin "AF22"
		)
		(pin "AF23"
		)
		(pin "AF25"
		)
		(pin "AG20"
		)
		(pin "AG22"
		)
		(pin "AG23"
		)
		(pin "AG24"
		)
		(pin "AG25"
		)
		(pin "AH20"
		)
		(pin "AH21"
		)
		(pin "AH22"
		)
		(pin "AH24"
		)
		(pin "AH25"
		)
		(pin "AJ21"
		)
		(pin "AJ22"
		)
		(pin "AJ23"
		)
		(pin "AJ24"
		)
		(pin "AK20"
		)
		(pin "AK21"
		)
		(pin "AK23"
		)
		(pin "AK24"
		)
		(pin "AK25"
		)
		(pin "Y20"
		)
		(pin "Y21"
		)
		(pin "Y23"
		)
		(pin "Y24"
		)
		(pin "P24"
		)
		(pin "P26"
		)
		(pin "P27"
		)
		(pin "P28"
		)
		(pin "P29"
		)
		(pin "R19"
		)
		(pin "R20"
		)
		(pin "R21"
		)
		(pin "R23"
		)
		(pin "R24"
		)
		(pin "R25"
		)
		(pin "R26"
		)
		(pin "R28"
		)
		(pin "R29"
		)
		(pin "R30"
		)
		(pin "T20"
		)
		(pin "T21"
		)
		(pin "T22"
		)
		(pin "T23"
		)
		(pin "T25"
		)
		(pin "T26"
		)
		(pin "T27"
		)
		(pin "T28"
		)
		(pin "T30"
		)
		(pin "U19"
		)
		(pin "U20"
		)
		(pin "U22"
		)
		(pin "U23"
		)
		(pin "U24"
		)
		(pin "U25"
		)
		(pin "U27"
		)
		(pin "U28"
		)
		(pin "U29"
		)
		(pin "U30"
		)
		(pin "V19"
		)
		(pin "V20"
		)
		(pin "V21"
		)
		(pin "V22"
		)
		(pin "V24"
		)
		(pin "V25"
		)
		(pin "V26"
		)
		(pin "V27"
		)
		(pin "V29"
		)
		(pin "V30"
		)
		(pin "W19"
		)
		(pin "W21"
		)
		(pin "W22"
		)
		(pin "W23"
		)
		(pin "W24"
		)
		(pin "W26"
		)
		(pin "A23"
		)
		(pin "A25"
		)
		(pin "A26"
		)
		(pin "A27"
		)
		(pin "A28"
		)
		(pin "A30"
		)
		(pin "B23"
		)
		(pin "B24"
		)
		(pin "B25"
		)
		(pin "B27"
		)
		(pin "B28"
		)
		(pin "B29"
		)
		(pin "B30"
		)
		(pin "C24"
		)
		(pin "C25"
		)
		(pin "C26"
		)
		(pin "C27"
		)
		(pin "C29"
		)
		(pin "C30"
		)
		(pin "D23"
		)
		(pin "D24"
		)
		(pin "D26"
		)
		(pin "D27"
		)
		(pin "D28"
		)
		(pin "D29"
		)
		(pin "E23"
		)
		(pin "E24"
		)
		(pin "E25"
		)
		(pin "E26"
		)
		(pin "B2"
		)
		(pin "B5"
		)
		(pin "B6"
		)
		(pin "C3"
		)
		(pin "C4"
		)
		(pin "E28"
		)
		(pin "E29"
		)
		(pin "E30"
		)
		(pin "F23"
		)
		(pin "F25"
		)
		(pin "F26"
		)
		(pin "F27"
		)
		(pin "F28"
		)
		(pin "F30"
		)
		(pin "G23"
		)
		(pin "G24"
		)
		(pin "G25"
		)
		(pin "G27"
		)
		(pin "G28"
		)
		(pin "G29"
		)
		(pin "G30"
		)
		(pin "H24"
		)
		(pin "H25"
		)
		(pin "H26"
		)
		(pin "H27"
		)
		(pin "H30"
		)
		(pin "A11"
		)
		(pin "A12"
		)
		(pin "A13"
		)
		(pin "A15"
		)
		(pin "B12"
		)
		(pin "B13"
		)
		(pin "B14"
		)
		(pin "B15"
		)
		(pin "C11"
		)
		(pin "C12"
		)
		(pin "C14"
		)
		(pin "C15"
		)
		(pin "D11"
		)
		(pin "D12"
		)
		(pin "D13"
		)
		(pin "D14"
		)
		(pin "E11"
		)
		(pin "E13"
		)
		(pin "E14"
		)
		(pin "E15"
		)
		(pin "E16"
		)
		(pin "F11"
		)
		(pin "F12"
		)
		(pin "F13"
		)
		(pin "F15"
		)
		(pin "F16"
		)
		(pin "G12"
		)
		(pin "G13"
		)
		(pin "G14"
		)
		(pin "G15"
		)
		(pin "H11"
		)
		(pin "H12"
		)
		(pin "H14"
		)
		(pin "H15"
		)
		(pin "H16"
		)
		(pin "J11"
		)
		(pin "J12"
		)
		(pin "J13"
		)
		(pin "J14"
		)
		(pin "J16"
		)
		(pin "K11"
		)
		(pin "K13"
		)
		(pin "K14"
		)
		(pin "K15"
		)
		(pin "K16"
		)
		(pin "L11"
		)
		(pin "L12"
		)
		(pin "L13"
		)
		(pin "L15"
		)
		(pin "L16"
		)
		(pin "AA10"
		)
		(pin "AA11"
		)
		(pin "AA12"
		)
		(pin "AA13"
		)
		(pin "AA8"
		)
		(pin "AB10"
		)
		(pin "AB12"
		)
		(pin "AB13"
		)
		(pin "AB8"
		)
		(pin "AB9"
		)
		(pin "AC10"
		)
		(pin "AC11"
		)
		(pin "AC12"
		)
		(pin "AC9"
		)
		(pin "AD11"
		)
		(pin "AD12"
		)
		(pin "AD13"
		)
		(pin "AD8"
		)
		(pin "AD9"
		)
		(pin "AE10"
		)
		(pin "AE11"
		)
		(pin "AE13"
		)
		(pin "AE8"
		)
		(pin "AE9"
		)
		(pin "AF10"
		)
		(pin "AF11"
		)
		(pin "AF12"
		)
		(pin "AF13"
		)
		(pin "AG10"
		)
		(pin "AG12"
		)
		(pin "AG13"
		)
		(pin "AG9"
		)
		(pin "AH10"
		)
		(pin "AH11"
		)
		(pin "AH12"
		)
		(pin "AH14"
		)
		(pin "AH9"
		)
		(pin "AJ11"
		)
		(pin "AJ12"
		)
		(pin "AJ13"
		)
		(pin "AJ14"
		)
		(pin "AJ9"
		)
		(pin "AK10"
		)
		(pin "AK11"
		)
		(pin "AK13"
		)
		(pin "AK14"
		)
		(pin "AK9"
		)
		(pin "Y10"
		)
		(pin "Y11"
		)
		(pin "Y13"
		)
		(pin "A3"
		)
		(pin "A4"
		)
		(pin "A7"
		)
		(pin "A8"
		)
		(pin "AA3"
		)
		(pin "AA4"
		)
		(pin "B1"
		)
		(pin "G16"
		)
		(pin "G2"
		)
		(pin "G26"
		)
		(pin "G6"
		)
		(pin "G9"
		)
		(pin "H13"
		)
		(pin "H23"
		)
		(pin "H4"
		)
		(pin "H8"
		)
		(pin "H9"
		)
		(pin "J1"
		)
		(pin "J10"
		)
		(pin "C7"
		)
		(pin "C8"
		)
		(pin "D1"
		)
		(pin "D2"
		)
		(pin "D5"
		)
		(pin "D6"
		)
		(pin "E3"
		)
		(pin "E4"
		)
		(pin "E7"
		)
		(pin "E8"
		)
		(pin "F1"
		)
		(pin "F2"
		)
		(pin "F5"
		)
		(pin "F6"
		)
		(pin "G3"
		)
		(pin "G4"
		)
		(pin "G7"
		)
		(pin "G8"
		)
		(pin "H1"
		)
		(pin "H2"
		)
		(pin "H5"
		)
		(pin "H6"
		)
		(pin "J3"
		)
		(pin "J4"
		)
		(pin "J7"
		)
		(pin "J8"
		)
		(pin "K1"
		)
		(pin "K2"
		)
		(pin "K5"
		)
		(pin "K6"
		)
		(pin "L3"
		)
		(pin "L4"
		)
		(pin "L7"
		)
		(pin "L8"
		)
		(pin "M1"
		)
		(pin "M2"
		)
		(pin "M5"
		)
		(pin "M6"
		)
		(pin "N3"
		)
		(pin "N4"
		)
		(pin "N7"
		)
		(pin "N8"
		)
		(pin "P1"
		)
		(pin "P2"
		)
		(pin "P5"
		)
		(pin "P6"
		)
		(pin "R3"
		)
		(pin "R4"
		)
		(pin "R7"
		)
		(pin "R8"
		)
		(pin "T1"
		)
		(pin "T2"
		)
		(pin "T5"
		)
		(pin "T6"
		)
		(pin "U3"
		)
		(pin "U4"
		)
		(pin "U7"
		)
		(pin "U8"
		)
		(pin "V1"
		)
		(pin "V2"
		)
		(pin "V5"
		)
		(pin "V6"
		)
		(pin "W3"
		)
		(pin "W4"
		)
		(pin "Y1"
		)
		(pin "Y2"
		)
		(pin "Y5"
		)
		(pin "Y6"
		)
		(pin "A10"
		)
		(pin "AB1"
		)
		(pin "AB2"
		)
		(pin "AB5"
		)
		(pin "B10"
		)
		(pin "E10"
		)
		(pin "F10"
		)
		(pin "G10"
		)
		(pin "H10"
		)
		(pin "K10"
		)
		(pin "L10"
		)
		(pin "M10"
		)
		(pin "R14"
		)
		(pin "R15"
		)
		(pin "T14"
		)
		(pin "T15"
		)
		(pin "U14"
		)
		(pin "U15"
		)
		(pin "A19"
		)
		(pin "A29"
		)
		(pin "AA19"
		)
		(pin "AA29"
		)
		(pin "AA9"
		)
		(pin "AB16"
		)
		(pin "AB26"
		)
		(pin "AB6"
		)
		(pin "AC13"
		)
		(pin "AC23"
		)
		(pin "AC3"
		)
		(pin "AD10"
		)
		(pin "AD20"
		)
		(pin "AD30"
		)
		(pin "AE17"
		)
		(pin "AE27"
		)
		(pin "AE7"
		)
		(pin "AF14"
		)
		(pin "AF24"
		)
		(pin "AF4"
		)
		(pin "AG1"
		)
		(pin "AG11"
		)
		(pin "AG21"
		)
		(pin "AH18"
		)
		(pin "AH28"
		)
		(pin "AH8"
		)
		(pin "AJ15"
		)
		(pin "AJ25"
		)
		(pin "AJ5"
		)
		(pin "AK12"
		)
		(pin "AK2"
		)
		(pin "AK22"
		)
		(pin "B16"
		)
		(pin "B26"
		)
		(pin "C13"
		)
		(pin "C23"
		)
		(pin "D10"
		)
		(pin "D20"
		)
		(pin "D30"
		)
		(pin "E17"
		)
		(pin "E27"
		)
		(pin "F14"
		)
		(pin "F24"
		)
		(pin "G11"
		)
		(pin "G21"
		)
		(pin "H18"
		)
		(pin "H28"
		)
		(pin "J15"
		)
		(pin "J25"
		)
		(pin "K12"
		)
		(pin "K22"
		)
		(pin "L19"
		)
		(pin "L29"
		)
		(pin "M26"
		)
		(pin "N23"
		)
		(pin "P20"
		)
		(pin "P30"
		)
		(pin "R27"
		)
		(pin "T24"
		)
		(pin "T9"
		)
		(pin "U21"
		)
		(pin "V28"
		)
		(pin "W25"
		)
		(pin "Y12"
		)
		(pin "Y22"
		)
		(pin "A1"
		)
		(pin "A14"
		)
		(pin "A2"
		)
		(pin "A24"
		)
		(pin "A5"
		)
		(pin "A6"
		)
		(pin "A9"
		)
		(pin "AA1"
		)
		(pin "AA14"
		)
		(pin "AA2"
		)
		(pin "AA24"
		)
		(pin "AA5"
		)
		(pin "AA6"
		)
		(pin "AA7"
		)
		(pin "AB11"
		)
		(pin "AB21"
		)
		(pin "AB3"
		)
		(pin "AB4"
		)
		(pin "AC18"
		)
		(pin "AC28"
		)
		(pin "AC8"
		)
		(pin "AD15"
		)
		(pin "AD25"
		)
		(pin "AD5"
		)
		(pin "AE12"
		)
		(pin "AE2"
		)
		(pin "AE22"
		)
		(pin "AF19"
		)
		(pin "AF29"
		)
		(pin "AF9"
		)
		(pin "AG16"
		)
		(pin "AG26"
		)
		(pin "AG6"
		)
		(pin "AH13"
		)
		(pin "AH23"
		)
		(pin "AH3"
		)
		(pin "AJ10"
		)
		(pin "AJ20"
		)
		(pin "AJ30"
		)
		(pin "AK17"
		)
		(pin "AK27"
		)
		(pin "AK7"
		)
		(pin "B11"
		)
		(pin "B21"
		)
		(pin "B4"
		)
		(pin "B8"
		)
		(pin "B9"
		)
		(pin "C1"
		)
		(pin "C10"
		)
		(pin "C18"
		)
		(pin "C2"
		)
		(pin "C28"
		)
		(pin "C6"
		)
		(pin "C9"
		)
		(pin "D15"
		)
		(pin "D25"
		)
		(pin "D4"
		)
		(pin "D8"
		)
		(pin "D9"
		)
		(pin "E1"
		)
		(pin "E12"
		)
		(pin "E2"
		)
		(pin "E22"
		)
		(pin "E6"
		)
		(pin "E9"
		)
		(pin "F19"
		)
		(pin "F29"
		)
		(pin "F4"
		)
		(pin "F8"
		)
		(pin "F9"
		)
		(pin "G1"
		)
		(pin "J2"
		)
		(pin "J20"
		)
		(pin "J30"
		)
		(pin "J6"
		)
		(pin "J9"
		)
		(pin "K17"
		)
		(pin "K27"
		)
		(pin "K4"
		)
		(pin "K8"
		)
		(pin "K9"
		)
		(pin "L1"
		)
		(pin "L14"
		)
		(pin "L2"
		)
		(pin "L24"
		)
		(pin "L6"
		)
		(pin "L9"
		)
		(pin "M11"
		)
		(pin "M12"
		)
		(pin "M13"
		)
		(pin "M14"
		)
		(pin "M15"
		)
		(pin "M16"
		)
		(pin "M17"
		)
		(pin "M18"
		)
		(pin "M21"
		)
		(pin "M4"
		)
		(pin "M8"
		)
		(pin "M9"
		)
		(pin "N1"
		)
		(pin "N10"
		)
		(pin "N11"
		)
		(pin "N12"
		)
		(pin "N13"
		)
		(pin "N14"
		)
		(pin "N15"
		)
		(pin "N16"
		)
		(pin "N17"
		)
		(pin "N18"
		)
		(pin "N2"
		)
		(pin "N28"
		)
		(pin "N6"
		)
		(pin "N9"
		)
		(pin "P10"
		)
		(pin "P11"
		)
		(pin "P12"
		)
		(pin "P13"
		)
		(pin "P14"
		)
		(pin "P15"
		)
		(pin "P16"
		)
		(pin "P17"
		)
		(pin "P18"
		)
		(pin "P25"
		)
		(pin "P4"
		)
		(pin "P8"
		)
		(pin "P9"
		)
		(pin "R1"
		)
		(pin "R10"
		)
		(pin "R11"
		)
		(pin "R12"
		)
		(pin "R13"
		)
		(pin "R16"
		)
		(pin "R17"
		)
		(pin "R18"
		)
		(pin "R2"
		)
		(pin "R22"
		)
		(pin "R6"
		)
		(pin "R9"
		)
		(pin "T10"
		)
		(pin "T11"
		)
		(pin "T12"
		)
		(pin "T13"
		)
		(pin "T16"
		)
		(pin "T17"
		)
		(pin "T18"
		)
		(pin "T19"
		)
		(pin "T29"
		)
		(pin "T4"
		)
		(pin "T8"
		)
		(pin "U1"
		)
		(pin "U10"
		)
		(pin "U11"
		)
		(pin "U12"
		)
		(pin "U13"
		)
		(pin "U16"
		)
		(pin "U17"
		)
		(pin "U18"
		)
		(pin "U2"
		)
		(pin "U26"
		)
		(pin "U6"
		)
		(pin "U9"
		)
		(pin "V10"
		)
		(pin "V11"
		)
		(pin "V12"
		)
		(pin "V13"
		)
		(pin "V14"
		)
		(pin "V15"
		)
		(pin "V16"
		)
		(pin "V17"
		)
		(pin "V18"
		)
		(pin "V23"
		)
		(pin "V4"
		)
		(pin "V8"
		)
		(pin "V9"
		)
		(pin "W1"
		)
		(pin "W10"
		)
		(pin "W11"
		)
		(pin "W12"
		)
		(pin "W13"
		)
		(pin "W14"
		)
		(pin "W15"
		)
		(pin "W16"
		)
		(pin "W17"
		)
		(pin "W18"
		)
		(pin "W2"
		)
		(pin "W20"
		)
		(pin "W30"
		)
		(pin "W6"
		)
		(pin "W9"
		)
		(pin "Y17"
		)
		(pin "Y27"
		)
		(pin "Y3"
		)
		(pin "Y4"
		)
		(pin "Y7"
		)
		(pin "Y8"
		)
		(pin "Y9"
		)
		(pin "AA25"
		)
		(pin "AA26"
		)
		(pin "AA27"
		)
		(pin "AA28"
		)
		(pin "AA30"
		)
		(pin "AB25"
		)
		(pin "AB27"
		)
		(pin "AB28"
		)
		(pin "AB29"
		)
		(pin "AB30"
		)
		(pin "AC26"
		)
		(pin "AC27"
		)
		(pin "AC29"
		)
		(pin "AC30"
		)
		(pin "AD26"
		)
		(pin "AD27"
		)
		(pin "AD28"
		)
		(pin "AD29"
		)
		(pin "AE26"
		)
		(pin "AE28"
		)
		(pin "AE29"
		)
		(pin "AE30"
		)
		(pin "AF26"
		)
		(pin "AF27"
		)
		(pin "AF28"
		)
		(pin "AF30"
		)
		(pin "AG27"
		)
		(pin "AG28"
		)
		(pin "AG29"
		)
		(pin "AG30"
		)
		(pin "AH26"
		)
		(pin "AH27"
		)
		(pin "AH29"
		)
		(pin "AH30"
		)
		(pin "AJ26"
		)
		(pin "AJ27"
		)
		(pin "AJ28"
		)
		(pin "AJ29"
		)
		(pin "AK26"
		)
		(pin "AK28"
		)
		(pin "AK29"
		)
		(pin "AK30"
		)
		(pin "W27"
		)
		(pin "W28"
		)
		(pin "W29"
		)
		(pin "Y25"
		)
		(pin "Y26"
		)
		(pin "Y28"
		)
		(pin "Y29"
		)
		(pin "Y30"
		)
		(pin "H29"
		)
		(pin "J21"
		)
		(pin "J22"
		)
		(pin "J23"
		)
		(pin "J24"
		)
		(pin "J26"
		)
		(pin "J27"
		)
		(pin "J28"
		)
		(pin "J29"
		)
		(pin "K21"
		)
		(pin "K23"
		)
		(pin "K24"
		)
		(pin "K25"
		)
		(pin "K26"
		)
		(pin "K28"
		)
		(pin "K29"
		)
		(pin "K30"
		)
		(pin "L20"
		)
		(pin "L21"
		)
		(pin "L22"
		)
		(pin "L23"
		)
		(pin "L25"
		)
		(pin "L26"
		)
		(pin "L27"
		)
		(pin "L28"
		)
		(pin "L30"
		)
		(pin "M19"
		)
		(pin "M20"
		)
		(pin "M22"
		)
		(pin "M23"
		)
		(pin "M24"
		)
		(pin "M25"
		)
		(pin "M27"
		)
		(pin "M28"
		)
		(pin "M29"
		)
		(pin "M30"
		)
		(pin "N19"
		)
		(pin "N20"
		)
		(pin "N21"
		)
		(pin "N22"
		)
		(pin "N24"
		)
		(pin "N25"
		)
		(pin "N26"
		)
		(pin "N27"
		)
		(pin "N29"
		)
		(pin "N30"
		)
		(pin "P19"
		)
		(pin "P21"
		)
		(pin "P22"
		)
		(pin "P23"
		)
		(pin "A16"
		)
		(pin "A17"
		)
		(pin "A18"
		)
		(pin "A20"
		)
		(pin "A21"
		)
		(pin "A22"
		)
		(pin "B17"
		)
		(pin "B18"
		)
		(pin "B19"
		)
		(pin "B20"
		)
		(pin "B22"
		)
		(pin "C16"
		)
		(pin "C17"
		)
		(pin "C19"
		)
		(pin "C20"
		)
		(pin "C21"
		)
		(pin "C22"
		)
		(pin "D16"
		)
		(pin "D17"
		)
		(pin "D18"
		)
		(pin "D19"
		)
		(pin "D21"
		)
		(pin "D22"
		)
		(pin "E18"
		)
		(pin "E19"
		)
		(pin "E20"
		)
		(pin "E21"
		)
		(pin "F17"
		)
		(pin "F18"
		)
		(pin "F20"
		)
		(pin "F21"
		)
		(pin "F22"
		)
		(pin "G17"
		)
		(pin "G18"
		)
		(pin "G19"
		)
		(pin "G20"
		)
		(pin "G22"
		)
		(pin "H17"
		)
		(pin "H19"
		)
		(pin "H20"
		)
		(pin "H21"
		)
		(pin "H22"
		)
		(pin "J17"
		)
		(pin "J18"
		)
		(pin "J19"
		)
		(pin "K18"
		)
		(pin "K19"
		)
		(pin "K20"
		)
		(pin "L17"
		)
		(pin "L18"
		)
		(pin "AA15"
		)
		(pin "AA16"
		)
		(pin "AA17"
		)
		(pin "AA18"
		)
		(pin "AB14"
		)
		(pin "AB15"
		)
		(pin "AB17"
		)
		(pin "AB18"
		)
		(pin "AB19"
		)
		(pin "AC14"
		)
		(pin "AC15"
		)
		(pin "AC16"
		)
		(pin "AC17"
		)
		(pin "AC19"
		)
		(pin "AD14"
		)
		(pin "AD16"
		)
		(pin "AD17"
		)
		(pin "AD18"
		)
		(pin "AD19"
		)
		(pin "AE14"
		)
		(pin "AE15"
		)
		(pin "AE16"
		)
		(pin "AE18"
		)
		(pin "AE19"
		)
		(pin "AF15"
		)
		(pin "AF16"
		)
		(pin "AF17"
		)
		(pin "AF18"
		)
		(pin "AG14"
		)
		(pin "AG15"
		)
		(pin "AG17"
		)
		(pin "AG18"
		)
		(pin "AG19"
		)
		(pin "AH15"
		)
		(pin "AH16"
		)
		(pin "AH17"
		)
		(pin "AH19"
		)
		(pin "AJ16"
		)
		(pin "AJ17"
		)
		(pin "AJ18"
		)
		(pin "AJ19"
		)
		(pin "AK15"
		)
		(pin "AK16"
		)
		(pin "AK18"
		)
		(pin "AK19"
		)
		(pin "Y14"
		)
		(pin "Y15"
		)
		(pin "Y16"
		)
		(pin "Y18"
		)
		(pin "Y19"
		)
		(pin "AB7"
		)
		(pin "AC1"
		)
		(pin "AC2"
		)
		(pin "AC4"
		)
		(pin "AC5"
		)
		(pin "AC6"
		)
		(pin "AC7"
		)
		(pin "AD1"
		)
		(pin "AD2"
		)
		(pin "AD3"
		)
		(pin "AD4"
		)
		(pin "AD6"
		)
		(pin "AD7"
		)
		(pin "AE1"
		)
		(pin "AE3"
		)
		(pin "AE4"
		)
		(pin "AE5"
		)
		(pin "AE6"
		)
		(pin "AF1"
		)
		(pin "AF2"
		)
		(pin "AF3"
		)
		(pin "AF5"
		)
		(pin "AF6"
		)
		(pin "AF7"
		)
		(pin "AF8"
		)
		(pin "AG2"
		)
		(pin "AG3"
		)
		(pin "AG4"
		)
		(pin "AG5"
		)
		(pin "AG7"
		)
		(pin "AG8"
		)
		(pin "AH1"
		)
		(pin "AH2"
		)
		(pin "AH4"
		)
		(pin "AH5"
		)
		(pin "AH6"
		)
		(pin "AH7"
		)
		(pin "AJ1"
		)
		(pin "AJ2"
		)
		(pin "AJ3"
		)
		(pin "AJ4"
		)
		(pin "AJ6"
		)
		(pin "AJ7"
		)
		(pin "AJ8"
		)
		(pin "AK1"
		)
		(pin "AK3"
		)
		(pin "AK4"
		)
		(pin "AK5"
		)
		(pin "AK6"
		)
		(pin "AK8"
		)
		(instances
			(project "k410t-devboard"
				(path ""
					(reference "U1")
					(unit 8)
				)
			)
		)
	)
	(symbol
		(lib_id "antmicroCapacitors0603:C_47u_0603")
		(at 161.29 220.98 270)
		(mirror x)
		(unit 1)
		(exclude_from_sim no)
		(in_bom yes)
		(on_board yes)
		(dnp no)
		(property "Reference" "C376"
			(at 160.655 216.535 90)
			(effects
				(font
					(size 1.27 1.27)
				)
				(justify right)
			)
		)
		(property "Value" "C_47u_0603"
			(at 151.13 200.66 0)
			(effects
				(font
					(size 1.27 1.27)
					(thickness 0.15)
				)
				(justify left bottom)
				(hide yes)
			)
		)
		(property "Footprint" "antmicro-footprints:C_0603_1608Metric"
			(at 148.59 200.66 0)
			(effects
				(font
					(size 1.27 1.27)
					(thickness 0.15)
				)
				(justify left bottom)
				(hide yes)
			)
		)
		(property "Datasheet" "https://www.murata.com/products/productdetail?partno=GRM188R60J476ME15%23"
			(at 146.05 200.66 0)
			(effects
				(font
					(size 1.27 1.27)
					(thickness 0.15)
				)
				(justify left bottom)
				(hide yes)
			)
		)
		(property "Description" ""
			(at 161.29 220.98 0)
			(effects
				(font
					(size 1.27 1.27)
				)
			)
		)
		(property "Manufacturer" "Murata"
			(at 140.97 200.66 0)
			(effects
				(font
					(size 1.27 1.27)
					(thickness 0.15)
				)
				(justify left bottom)
				(hide yes)
			)
		)
		(property "MPN" "GRM188R60J476ME15D"
			(at 143.51 200.66 0)
			(effects
				(font
					(size 1.27 1.27)
					(thickness 0.15)
				)
				(justify left bottom)
				(hide yes)
			)
		)
		(property "Val" "47u"
			(at 160.655 220.345 90)
			(effects
				(font
					(size 1.27 1.27)
					(thickness 0.15)
				)
				(justify right)
			)
		)
		(property "License" "Apache-2.0"
			(at 138.43 200.66 0)
			(effects
				(font
					(size 1.27 1.27)
					(thickness 0.15)
				)
				(justify left bottom)
				(hide yes)
			)
		)
		(property "Author" "Antmicro"
			(at 135.89 200.66 0)
			(effects
				(font
					(size 1.27 1.27)
					(thickness 0.15)
				)
				(justify left bottom)
				(hide yes)
			)
		)
		(property "Voltage" ""
			(at 133.35 200.66 0)
			(effects
				(font
					(size 1.27 1.27)
				)
				(justify left bottom)
				(hide yes)
			)
		)
		(property "Dielectric" ""
			(at 130.81 200.66 0)
			(effects
				(font
					(size 1.27 1.27)
				)
				(justify left bottom)
				(hide yes)
			)
		)
		(pin "1"
		)
		(pin "2"
		)
		(instances
			(project "k410t-devboard"
				(path ""
					(reference "C376")
					(unit 1)
				)
			)
		)
	)
	(symbol
		(lib_id "antmicroCapacitorsmisc:C_100n_0201")
		(at 233.68 93.98 90)
		(unit 1)
		(exclude_from_sim no)
		(in_bom yes)
		(on_board yes)
		(dnp no)
		(property "Reference" "C159"
			(at 234.315 89.535 90)
			(effects
				(font
					(size 1.27 1.27)
				)
				(justify right)
			)
		)
		(property "Value" "C_100n_0201"
			(at 243.84 73.66 0)
			(effects
				(font
					(size 1.27 1.27)
					(thickness 0.15)
				)
				(justify left bottom)
				(hide yes)
			)
		)
		(property "Footprint" "antmicro-footprints:C_0201"
			(at 246.38 73.66 0)
			(effects
				(font
					(size 1.27 1.27)
					(thickness 0.15)
				)
				(justify left bottom)
				(hide yes)
			)
		)
		(property "Datasheet" "https://www.yageo.com/en/Chart/Download/pdf/CC0201KRX6S5BB104"
			(at 248.92 73.66 0)
			(effects
				(font
					(size 1.27 1.27)
					(thickness 0.15)
				)
				(justify left bottom)
				(hide yes)
			)
		)
		(property "Description" ""
			(at 233.68 93.98 0)
			(effects
				(font
					(size 1.27 1.27)
				)
			)
		)
		(property "Manufacturer" "YAGEO"
			(at 254 73.66 0)
			(effects
				(font
					(size 1.27 1.27)
					(thickness 0.15)
				)
				(justify left bottom)
				(hide yes)
			)
		)
		(property "MPN" "CC0201KRX6S5BB104"
			(at 251.46 73.66 0)
			(effects
				(font
					(size 1.27 1.27)
					(thickness 0.15)
				)
				(justify left bottom)
				(hide yes)
			)
		)
		(property "Val" "100n"
			(at 234.315 93.345 90)
			(effects
				(font
					(size 1.27 1.27)
					(thickness 0.15)
				)
				(justify right)
			)
		)
		(property "License" "Apache-2.0"
			(at 256.54 73.66 0)
			(effects
				(font
					(size 1.27 1.27)
					(thickness 0.15)
				)
				(justify left bottom)
				(hide yes)
			)
		)
		(property "Author" "Antmicro"
			(at 259.08 73.66 0)
			(effects
				(font
					(size 1.27 1.27)
					(thickness 0.15)
				)
				(justify left bottom)
				(hide yes)
			)
		)
		(property "Voltage" ""
			(at 261.62 73.66 0)
			(effects
				(font
					(size 1.27 1.27)
				)
				(justify left bottom)
				(hide yes)
			)
		)
		(property "Dielectric" ""
			(at 264.16 73.66 0)
			(effects
				(font
					(size 1.27 1.27)
				)
				(justify left bottom)
				(hide yes)
			)
		)
		(pin "1"
		)
		(pin "2"
		)
		(instances
			(project "k410t-devboard"
				(path ""
					(reference "C159")
					(unit 1)
				)
			)
		)
	)
	(symbol
		(lib_id "antmicroCapacitorsmisc:C_4u7_0201")
		(at 207.01 201.93 270)
		(mirror x)
		(unit 1)
		(exclude_from_sim no)
		(in_bom yes)
		(on_board yes)
		(dnp no)
		(property "Reference" "C8"
			(at 206.375 197.485 90)
			(effects
				(font
					(size 1.27 1.27)
				)
				(justify right)
			)
		)
		(property "Value" "C_4u7_0201"
			(at 196.85 181.61 0)
			(effects
				(font
					(size 1.27 1.27)
					(thickness 0.15)
				)
				(justify left bottom)
				(hide yes)
			)
		)
		(property "Footprint" "antmicro-footprints:C_0201"
			(at 194.31 181.61 0)
			(effects
				(font
					(size 1.27 1.27)
					(thickness 0.15)
				)
				(justify left bottom)
				(hide yes)
			)
		)
		(property "Datasheet" "https://www.murata.com/products/productdetail?partno=GRM035R60J475ME15%23"
			(at 191.77 181.61 0)
			(effects
				(font
					(size 1.27 1.27)
					(thickness 0.15)
				)
				(justify left bottom)
				(hide yes)
			)
		)
		(property "Description" ""
			(at 207.01 201.93 0)
			(effects
				(font
					(size 1.27 1.27)
				)
			)
		)
		(property "Manufacturer" "Murata"
			(at 186.69 181.61 0)
			(effects
				(font
					(size 1.27 1.27)
					(thickness 0.15)
				)
				(justify left bottom)
				(hide yes)
			)
		)
		(property "MPN" "GRM035R60J475ME15D"
			(at 189.23 181.61 0)
			(effects
				(font
					(size 1.27 1.27)
					(thickness 0.15)
				)
				(justify left bottom)
				(hide yes)
			)
		)
		(property "Val" "4u7"
			(at 206.375 201.295 90)
			(effects
				(font
					(size 1.27 1.27)
					(thickness 0.15)
				)
				(justify right)
			)
		)
		(property "License" "Apache-2.0"
			(at 184.15 181.61 0)
			(effects
				(font
					(size 1.27 1.27)
					(thickness 0.15)
				)
				(justify left bottom)
				(hide yes)
			)
		)
		(property "Author" "Antmicro"
			(at 181.61 181.61 0)
			(effects
				(font
					(size 1.27 1.27)
					(thickness 0.15)
				)
				(justify left bottom)
				(hide yes)
			)
		)
		(property "Voltage" ""
			(at 179.07 181.61 0)
			(effects
				(font
					(size 1.27 1.27)
				)
				(justify left bottom)
				(hide yes)
			)
		)
		(property "Dielectric" ""
			(at 176.53 181.61 0)
			(effects
				(font
					(size 1.27 1.27)
				)
				(justify left bottom)
				(hide yes)
			)
		)
		(pin "1"
		)
		(pin "2"
		)
		(instances
			(project "k410t-devboard"
				(path ""
					(reference "C8")
					(unit 1)
				)
			)
		)
	)
	(symbol
		(lib_id "antmicroResistors0402:R_100R_0402")
		(at 224.79 66.04 0)
		(mirror x)
		(unit 1)
		(exclude_from_sim no)
		(in_bom yes)
		(on_board yes)
		(dnp no)
		(property "Reference" "R1"
			(at 227.33 60.96 0)
			(effects
				(font
					(size 1.27 1.27)
				)
			)
		)
		(property "Value" "R_100R_0402"
			(at 245.11 53.34 0)
			(effects
				(font
					(size 1.27 1.27)
					(thickness 0.15)
				)
				(justify left bottom)
				(hide yes)
			)
		)
		(property "Footprint" "antmicro-footprints:R_0402_1005Metric"
			(at 245.11 50.8 0)
			(effects
				(font
					(size 1.27 1.27)
					(thickness 0.15)
				)
				(justify left bottom)
				(hide yes)
			)
		)
		(property "Datasheet" "https://www.bourns.com/docs/product-datasheets/cr.pdf"
			(at 245.11 48.26 0)
			(effects
				(font
					(size 1.27 1.27)
					(thickness 0.15)
				)
				(justify left bottom)
				(hide yes)
			)
		)
		(property "Description" ""
			(at 224.79 66.04 0)
			(effects
				(font
					(size 1.27 1.27)
				)
			)
		)
		(property "Manufacturer" "Bourns"
			(at 245.11 43.18 0)
			(effects
				(font
					(size 1.27 1.27)
					(thickness 0.15)
				)
				(justify left bottom)
				(hide yes)
			)
		)
		(property "MPN" "CR0402-FX-1000GLF"
			(at 245.11 45.72 0)
			(effects
				(font
					(size 1.27 1.27)
					(thickness 0.15)
				)
				(justify left bottom)
				(hide yes)
			)
		)
		(property "Val" "100R"
			(at 227.33 63.5 0)
			(effects
				(font
					(size 1.27 1.27)
					(thickness 0.15)
				)
			)
		)
		(property "License" "Apache-2.0"
			(at 245.11 40.64 0)
			(effects
				(font
					(size 1.27 1.27)
					(thickness 0.15)
				)
				(justify left bottom)
				(hide yes)
			)
		)
		(property "Author" "Antmicro"
			(at 245.11 38.1 0)
			(effects
				(font
					(size 1.27 1.27)
					(thickness 0.15)
				)
				(justify left bottom)
				(hide yes)
			)
		)
		(property "Tolerance" "1%"
			(at 245.11 55.88 0)
			(effects
				(font
					(size 1.27 1.27)
				)
				(justify left bottom)
				(hide yes)
			)
		)
		(pin "1"
		)
		(pin "2"
		)
		(instances
			(project "k410t-devboard"
				(path ""
					(reference "R1")
					(unit 1)
				)
			)
		)
	)
	(symbol
		(lib_id "antmicroGenericPinHeaders:PinHeader_2x3_P2.54mm_SMD")
		(at 379.73 241.3 0)
		(mirror y)
		(unit 1)
		(exclude_from_sim no)
		(in_bom yes)
		(on_board yes)
		(dnp no)
		(property "Reference" "J20"
			(at 374.65 238.76 0)
			(effects
				(font
					(size 1.27 1.27)
				)
			)
		)
		(property "Value" "PinHeader_2x3_P2.54mm_SMD"
			(at 354.33 248.92 0)
			(effects
				(font
					(size 1.27 1.27)
					(thickness 0.15)
				)
				(justify left bottom)
				(hide yes)
			)
		)
		(property "Footprint" "antmicro-footprints:PinHeader_2x3_P2.54mm_SMD"
			(at 354.33 251.46 0)
			(effects
				(font
					(size 1.27 1.27)
					(thickness 0.15)
				)
				(justify left bottom)
				(hide yes)
			)
		)
		(property "Datasheet" "https://www.molex.com/pdm_docs/sd/015910060_sd.pdf"
			(at 354.33 254 0)
			(effects
				(font
					(size 1.27 1.27)
					(thickness 0.15)
				)
				(justify left bottom)
				(hide yes)
			)
		)
		(property "Description" ""
			(at 379.73 241.3 0)
			(effects
				(font
					(size 1.27 1.27)
				)
			)
		)
		(property "MPN" "15910060"
			(at 354.33 256.54 0)
			(effects
				(font
					(size 1.27 1.27)
					(thickness 0.15)
				)
				(justify left bottom)
				(hide yes)
			)
		)
		(property "Manufacturer" "Molex"
			(at 354.33 259.08 0)
			(effects
				(font
					(size 1.27 1.27)
					(thickness 0.15)
				)
				(justify left bottom)
				(hide yes)
			)
		)
		(property "Author" "Antmicro"
			(at 354.33 261.62 0)
			(effects
				(font
					(size 1.27 1.27)
					(thickness 0.15)
				)
				(justify left bottom)
				(hide yes)
			)
		)
		(property "License" "Apache-2.0"
			(at 354.33 264.16 0)
			(effects
				(font
					(size 1.27 1.27)
					(thickness 0.15)
				)
				(justify left bottom)
				(hide yes)
			)
		)
		(pin "1"
		)
		(pin "2"
		)
		(pin "3"
		)
		(pin "4"
		)
		(pin "5"
		)
		(pin "6"
		)
		(instances
			(project "k410t-devboard"
				(path ""
					(reference "J20")
					(unit 1)
				)
			)
		)
	)
	(symbol
		(lib_id "antmicroCapacitorsmisc:C_4u7_0201")
		(at 157.48 93.98 90)
		(unit 1)
		(exclude_from_sim no)
		(in_bom yes)
		(on_board yes)
		(dnp no)
		(property "Reference" "C162"
			(at 158.115 89.535 90)
			(effects
				(font
					(size 1.27 1.27)
				)
				(justify right)
			)
		)
		(property "Value" "C_4u7_0201"
			(at 167.64 73.66 0)
			(effects
				(font
					(size 1.27 1.27)
					(thickness 0.15)
				)
				(justify left bottom)
				(hide yes)
			)
		)
		(property "Footprint" "antmicro-footprints:C_0201"
			(at 170.18 73.66 0)
			(effects
				(font
					(size 1.27 1.27)
					(thickness 0.15)
				)
				(justify left bottom)
				(hide yes)
			)
		)
		(property "Datasheet" "https://www.murata.com/products/productdetail?partno=GRM035R60J475ME15%23"
			(at 172.72 73.66 0)
			(effects
				(font
					(size 1.27 1.27)
					(thickness 0.15)
				)
				(justify left bottom)
				(hide yes)
			)
		)
		(property "Description" ""
			(at 157.48 93.98 0)
			(effects
				(font
					(size 1.27 1.27)
				)
			)
		)
		(property "Manufacturer" "Murata"
			(at 177.8 73.66 0)
			(effects
				(font
					(size 1.27 1.27)
					(thickness 0.15)
				)
				(justify left bottom)
				(hide yes)
			)
		)
		(property "MPN" "GRM035R60J475ME15D"
			(at 175.26 73.66 0)
			(effects
				(font
					(size 1.27 1.27)
					(thickness 0.15)
				)
				(justify left bottom)
				(hide yes)
			)
		)
		(property "Val" "4u7"
			(at 158.115 93.345 90)
			(effects
				(font
					(size 1.27 1.27)
					(thickness 0.15)
				)
				(justify right)
			)
		)
		(property "License" "Apache-2.0"
			(at 180.34 73.66 0)
			(effects
				(font
					(size 1.27 1.27)
					(thickness 0.15)
				)
				(justify left bottom)
				(hide yes)
			)
		)
		(property "Author" "Antmicro"
			(at 182.88 73.66 0)
			(effects
				(font
					(size 1.27 1.27)
					(thickness 0.15)
				)
				(justify left bottom)
				(hide yes)
			)
		)
		(property "Voltage" ""
			(at 185.42 73.66 0)
			(effects
				(font
					(size 1.27 1.27)
				)
				(justify left bottom)
				(hide yes)
			)
		)
		(property "Dielectric" ""
			(at 187.96 73.66 0)
			(effects
				(font
					(size 1.27 1.27)
				)
				(justify left bottom)
				(hide yes)
			)
		)
		(pin "1"
		)
		(pin "2"
		)
		(instances
			(project "k410t-devboard"
				(path ""
					(reference "C162")
					(unit 1)
				)
			)
		)
	)
	(symbol
		(lib_id "antmicroCapacitors0402:C_100n_0402")
		(at 176.53 238.76 270)
		(mirror x)
		(unit 1)
		(exclude_from_sim no)
		(in_bom yes)
		(on_board yes)
		(dnp no)
		(property "Reference" "C138"
			(at 175.895 234.315 90)
			(effects
				(font
					(size 1.27 1.27)
				)
				(justify right)
			)
		)
		(property "Value" "C_100n_0402"
			(at 166.37 218.44 0)
			(effects
				(font
					(size 1.27 1.27)
					(thickness 0.15)
				)
				(justify left bottom)
				(hide yes)
			)
		)
		(property "Footprint" "antmicro-footprints:C_0402_1005Metric"
			(at 163.83 218.44 0)
			(effects
				(font
					(size 1.27 1.27)
					(thickness 0.15)
				)
				(justify left bottom)
				(hide yes)
			)
		)
		(property "Datasheet" "https://www.murata.com/products/productdetail?partno=GRM155R61H104KE14%23"
			(at 161.29 218.44 0)
			(effects
				(font
					(size 1.27 1.27)
					(thickness 0.15)
				)
				(justify left bottom)
				(hide yes)
			)
		)
		(property "Description" ""
			(at 176.53 238.76 0)
			(effects
				(font
					(size 1.27 1.27)
				)
			)
		)
		(property "Manufacturer" "Murata"
			(at 156.21 218.44 0)
			(effects
				(font
					(size 1.27 1.27)
					(thickness 0.15)
				)
				(justify left bottom)
				(hide yes)
			)
		)
		(property "MPN" "GRM155R61H104KE14D"
			(at 158.75 218.44 0)
			(effects
				(font
					(size 1.27 1.27)
					(thickness 0.15)
				)
				(justify left bottom)
				(hide yes)
			)
		)
		(property "Val" "100n"
			(at 175.895 238.125 90)
			(effects
				(font
					(size 1.27 1.27)
					(thickness 0.15)
				)
				(justify right)
			)
		)
		(property "License" "Apache-2.0"
			(at 153.67 218.44 0)
			(effects
				(font
					(size 1.27 1.27)
					(thickness 0.15)
				)
				(justify left bottom)
				(hide yes)
			)
		)
		(property "Author" "Antmicro"
			(at 151.13 218.44 0)
			(effects
				(font
					(size 1.27 1.27)
					(thickness 0.15)
				)
				(justify left bottom)
				(hide yes)
			)
		)
		(property "Voltage" "50V"
			(at 148.59 218.44 0)
			(effects
				(font
					(size 1.27 1.27)
				)
				(justify left bottom)
				(hide yes)
			)
		)
		(property "Dielectric" "X5R"
			(at 146.05 218.44 0)
			(effects
				(font
					(size 1.27 1.27)
				)
				(justify left bottom)
				(hide yes)
			)
		)
		(pin "1"
		)
		(pin "2"
		)
		(instances
			(project "k410t-devboard"
				(path ""
					(reference "C138")
					(unit 1)
				)
			)
		)
	)
	(symbol
		(lib_id "antmicroCapacitors0603:C_47u_0603")
		(at 153.67 238.76 270)
		(mirror x)
		(unit 1)
		(exclude_from_sim no)
		(in_bom yes)
		(on_board yes)
		(dnp no)
		(property "Reference" "C383"
			(at 153.035 234.315 90)
			(effects
				(font
					(size 1.27 1.27)
				)
				(justify right)
			)
		)
		(property "Value" "C_47u_0603"
			(at 143.51 218.44 0)
			(effects
				(font
					(size 1.27 1.27)
					(thickness 0.15)
				)
				(justify left bottom)
				(hide yes)
			)
		)
		(property "Footprint" "antmicro-footprints:C_0603_1608Metric"
			(at 140.97 218.44 0)
			(effects
				(font
					(size 1.27 1.27)
					(thickness 0.15)
				)
				(justify left bottom)
				(hide yes)
			)
		)
		(property "Datasheet" "https://www.murata.com/products/productdetail?partno=GRM188R60J476ME15%23"
			(at 138.43 218.44 0)
			(effects
				(font
					(size 1.27 1.27)
					(thickness 0.15)
				)
				(justify left bottom)
				(hide yes)
			)
		)
		(property "Description" ""
			(at 153.67 238.76 0)
			(effects
				(font
					(size 1.27 1.27)
				)
			)
		)
		(property "Manufacturer" "Murata"
			(at 133.35 218.44 0)
			(effects
				(font
					(size 1.27 1.27)
					(thickness 0.15)
				)
				(justify left bottom)
				(hide yes)
			)
		)
		(property "MPN" "GRM188R60J476ME15D"
			(at 135.89 218.44 0)
			(effects
				(font
					(size 1.27 1.27)
					(thickness 0.15)
				)
				(justify left bottom)
				(hide yes)
			)
		)
		(property "Val" "47u"
			(at 153.035 238.125 90)
			(effects
				(font
					(size 1.27 1.27)
					(thickness 0.15)
				)
				(justify right)
			)
		)
		(property "License" "Apache-2.0"
			(at 130.81 218.44 0)
			(effects
				(font
					(size 1.27 1.27)
					(thickness 0.15)
				)
				(justify left bottom)
				(hide yes)
			)
		)
		(property "Author" "Antmicro"
			(at 128.27 218.44 0)
			(effects
				(font
					(size 1.27 1.27)
					(thickness 0.15)
				)
				(justify left bottom)
				(hide yes)
			)
		)
		(property "Voltage" ""
			(at 125.73 218.44 0)
			(effects
				(font
					(size 1.27 1.27)
				)
				(justify left bottom)
				(hide yes)
			)
		)
		(property "Dielectric" ""
			(at 123.19 218.44 0)
			(effects
				(font
					(size 1.27 1.27)
				)
				(justify left bottom)
				(hide yes)
			)
		)
		(pin "1"
		)
		(pin "2"
		)
		(instances
			(project "k410t-devboard"
				(path ""
					(reference "C383")
					(unit 1)
				)
			)
		)
	)
	(symbol
		(lib_id "antmicroCapacitors0402:C_100n_0402")
		(at 237.49 151.13 90)
		(unit 1)
		(exclude_from_sim no)
		(in_bom yes)
		(on_board yes)
		(dnp no)
		(property "Reference" "C72"
			(at 238.125 146.685 90)
			(effects
				(font
					(size 1.27 1.27)
				)
				(justify right)
			)
		)
		(property "Value" "C_100n_0402"
			(at 247.65 130.81 0)
			(effects
				(font
					(size 1.27 1.27)
					(thickness 0.15)
				)
				(justify left bottom)
				(hide yes)
			)
		)
		(property "Footprint" "antmicro-footprints:C_0402_1005Metric"
			(at 250.19 130.81 0)
			(effects
				(font
					(size 1.27 1.27)
					(thickness 0.15)
				)
				(justify left bottom)
				(hide yes)
			)
		)
		(property "Datasheet" "https://www.murata.com/products/productdetail?partno=GRM155R61H104KE14%23"
			(at 252.73 130.81 0)
			(effects
				(font
					(size 1.27 1.27)
					(thickness 0.15)
				)
				(justify left bottom)
				(hide yes)
			)
		)
		(property "Description" ""
			(at 237.49 151.13 0)
			(effects
				(font
					(size 1.27 1.27)
				)
			)
		)
		(property "Manufacturer" "Murata"
			(at 257.81 130.81 0)
			(effects
				(font
					(size 1.27 1.27)
					(thickness 0.15)
				)
				(justify left bottom)
				(hide yes)
			)
		)
		(property "MPN" "GRM155R61H104KE14D"
			(at 255.27 130.81 0)
			(effects
				(font
					(size 1.27 1.27)
					(thickness 0.15)
				)
				(justify left bottom)
				(hide yes)
			)
		)
		(property "Val" "100n"
			(at 238.125 150.495 90)
			(effects
				(font
					(size 1.27 1.27)
					(thickness 0.15)
				)
				(justify right)
			)
		)
		(property "License" "Apache-2.0"
			(at 260.35 130.81 0)
			(effects
				(font
					(size 1.27 1.27)
					(thickness 0.15)
				)
				(justify left bottom)
				(hide yes)
			)
		)
		(property "Author" "Antmicro"
			(at 262.89 130.81 0)
			(effects
				(font
					(size 1.27 1.27)
					(thickness 0.15)
				)
				(justify left bottom)
				(hide yes)
			)
		)
		(property "Voltage" "50V"
			(at 265.43 130.81 0)
			(effects
				(font
					(size 1.27 1.27)
				)
				(justify left bottom)
				(hide yes)
			)
		)
		(property "Dielectric" "X5R"
			(at 267.97 130.81 0)
			(effects
				(font
					(size 1.27 1.27)
				)
				(justify left bottom)
				(hide yes)
			)
		)
		(pin "1"
		)
		(pin "2"
		)
		(instances
			(project "k410t-devboard"
				(path ""
					(reference "C72")
					(unit 1)
				)
			)
		)
	)
	(symbol
		(lib_id "antmicroCapacitorsmisc:C_100n_0201")
		(at 187.96 93.98 90)
		(unit 1)
		(exclude_from_sim no)
		(in_bom yes)
		(on_board yes)
		(dnp no)
		(property "Reference" "C147"
			(at 188.595 89.535 90)
			(effects
				(font
					(size 1.27 1.27)
				)
				(justify right)
			)
		)
		(property "Value" "C_100n_0201"
			(at 198.12 73.66 0)
			(effects
				(font
					(size 1.27 1.27)
					(thickness 0.15)
				)
				(justify left bottom)
				(hide yes)
			)
		)
		(property "Footprint" "antmicro-footprints:C_0201"
			(at 200.66 73.66 0)
			(effects
				(font
					(size 1.27 1.27)
					(thickness 0.15)
				)
				(justify left bottom)
				(hide yes)
			)
		)
		(property "Datasheet" "https://www.yageo.com/en/Chart/Download/pdf/CC0201KRX6S5BB104"
			(at 203.2 73.66 0)
			(effects
				(font
					(size 1.27 1.27)
					(thickness 0.15)
				)
				(justify left bottom)
				(hide yes)
			)
		)
		(property "Description" ""
			(at 187.96 93.98 0)
			(effects
				(font
					(size 1.27 1.27)
				)
			)
		)
		(property "Manufacturer" "YAGEO"
			(at 208.28 73.66 0)
			(effects
				(font
					(size 1.27 1.27)
					(thickness 0.15)
				)
				(justify left bottom)
				(hide yes)
			)
		)
		(property "MPN" "CC0201KRX6S5BB104"
			(at 205.74 73.66 0)
			(effects
				(font
					(size 1.27 1.27)
					(thickness 0.15)
				)
				(justify left bottom)
				(hide yes)
			)
		)
		(property "Val" "100n"
			(at 188.595 93.345 90)
			(effects
				(font
					(size 1.27 1.27)
					(thickness 0.15)
				)
				(justify right)
			)
		)
		(property "License" "Apache-2.0"
			(at 210.82 73.66 0)
			(effects
				(font
					(size 1.27 1.27)
					(thickness 0.15)
				)
				(justify left bottom)
				(hide yes)
			)
		)
		(property "Author" "Antmicro"
			(at 213.36 73.66 0)
			(effects
				(font
					(size 1.27 1.27)
					(thickness 0.15)
				)
				(justify left bottom)
				(hide yes)
			)
		)
		(property "Voltage" ""
			(at 215.9 73.66 0)
			(effects
				(font
					(size 1.27 1.27)
				)
				(justify left bottom)
				(hide yes)
			)
		)
		(property "Dielectric" ""
			(at 218.44 73.66 0)
			(effects
				(font
					(size 1.27 1.27)
				)
				(justify left bottom)
				(hide yes)
			)
		)
		(pin "1"
		)
		(pin "2"
		)
		(instances
			(project "k410t-devboard"
				(path ""
					(reference "C147")
					(unit 1)
				)
			)
		)
	)
	(symbol
		(lib_id "antmicroCapacitors0603:C_47u_0603")
		(at 123.19 238.76 270)
		(mirror x)
		(unit 1)
		(exclude_from_sim no)
		(in_bom yes)
		(on_board yes)
		(dnp no)
		(property "Reference" "C387"
			(at 122.555 234.315 90)
			(effects
				(font
					(size 1.27 1.27)
				)
				(justify right)
			)
		)
		(property "Value" "C_47u_0603"
			(at 113.03 218.44 0)
			(effects
				(font
					(size 1.27 1.27)
					(thickness 0.15)
				)
				(justify left bottom)
				(hide yes)
			)
		)
		(property "Footprint" "antmicro-footprints:C_0603_1608Metric"
			(at 110.49 218.44 0)
			(effects
				(font
					(size 1.27 1.27)
					(thickness 0.15)
				)
				(justify left bottom)
				(hide yes)
			)
		)
		(property "Datasheet" "https://www.murata.com/products/productdetail?partno=GRM188R60J476ME15%23"
			(at 107.95 218.44 0)
			(effects
				(font
					(size 1.27 1.27)
					(thickness 0.15)
				)
				(justify left bottom)
				(hide yes)
			)
		)
		(property "Description" ""
			(at 123.19 238.76 0)
			(effects
				(font
					(size 1.27 1.27)
				)
			)
		)
		(property "Manufacturer" "Murata"
			(at 102.87 218.44 0)
			(effects
				(font
					(size 1.27 1.27)
					(thickness 0.15)
				)
				(justify left bottom)
				(hide yes)
			)
		)
		(property "MPN" "GRM188R60J476ME15D"
			(at 105.41 218.44 0)
			(effects
				(font
					(size 1.27 1.27)
					(thickness 0.15)
				)
				(justify left bottom)
				(hide yes)
			)
		)
		(property "Val" "47u"
			(at 122.555 238.125 90)
			(effects
				(font
					(size 1.27 1.27)
					(thickness 0.15)
				)
				(justify right)
			)
		)
		(property "License" "Apache-2.0"
			(at 100.33 218.44 0)
			(effects
				(font
					(size 1.27 1.27)
					(thickness 0.15)
				)
				(justify left bottom)
				(hide yes)
			)
		)
		(property "Author" "Antmicro"
			(at 97.79 218.44 0)
			(effects
				(font
					(size 1.27 1.27)
					(thickness 0.15)
				)
				(justify left bottom)
				(hide yes)
			)
		)
		(property "Voltage" ""
			(at 95.25 218.44 0)
			(effects
				(font
					(size 1.27 1.27)
				)
				(justify left bottom)
				(hide yes)
			)
		)
		(property "Dielectric" ""
			(at 92.71 218.44 0)
			(effects
				(font
					(size 1.27 1.27)
				)
				(justify left bottom)
				(hide yes)
			)
		)
		(pin "1"
		)
		(pin "2"
		)
		(instances
			(project "k410t-devboard"
				(path ""
					(reference "C387")
					(unit 1)
				)
			)
		)
	)
	(symbol
		(lib_id "antmicroCapacitorsmisc:C_100n_0201")
		(at 172.72 76.2 90)
		(unit 1)
		(exclude_from_sim no)
		(in_bom yes)
		(on_board yes)
		(dnp no)
		(property "Reference" "C144"
			(at 173.355 71.755 90)
			(effects
				(font
					(size 1.27 1.27)
				)
				(justify right)
			)
		)
		(property "Value" "C_100n_0201"
			(at 182.88 55.88 0)
			(effects
				(font
					(size 1.27 1.27)
					(thickness 0.15)
				)
				(justify left bottom)
				(hide yes)
			)
		)
		(property "Footprint" "antmicro-footprints:C_0201"
			(at 185.42 55.88 0)
			(effects
				(font
					(size 1.27 1.27)
					(thickness 0.15)
				)
				(justify left bottom)
				(hide yes)
			)
		)
		(property "Datasheet" "https://www.yageo.com/en/Chart/Download/pdf/CC0201KRX6S5BB104"
			(at 187.96 55.88 0)
			(effects
				(font
					(size 1.27 1.27)
					(thickness 0.15)
				)
				(justify left bottom)
				(hide yes)
			)
		)
		(property "Description" ""
			(at 172.72 76.2 0)
			(effects
				(font
					(size 1.27 1.27)
				)
			)
		)
		(property "Manufacturer" "YAGEO"
			(at 193.04 55.88 0)
			(effects
				(font
					(size 1.27 1.27)
					(thickness 0.15)
				)
				(justify left bottom)
				(hide yes)
			)
		)
		(property "MPN" "CC0201KRX6S5BB104"
			(at 190.5 55.88 0)
			(effects
				(font
					(size 1.27 1.27)
					(thickness 0.15)
				)
				(justify left bottom)
				(hide yes)
			)
		)
		(property "Val" "100n"
			(at 173.355 75.565 90)
			(effects
				(font
					(size 1.27 1.27)
					(thickness 0.15)
				)
				(justify right)
			)
		)
		(property "License" "Apache-2.0"
			(at 195.58 55.88 0)
			(effects
				(font
					(size 1.27 1.27)
					(thickness 0.15)
				)
				(justify left bottom)
				(hide yes)
			)
		)
		(property "Author" "Antmicro"
			(at 198.12 55.88 0)
			(effects
				(font
					(size 1.27 1.27)
					(thickness 0.15)
				)
				(justify left bottom)
				(hide yes)
			)
		)
		(property "Voltage" ""
			(at 200.66 55.88 0)
			(effects
				(font
					(size 1.27 1.27)
				)
				(justify left bottom)
				(hide yes)
			)
		)
		(property "Dielectric" ""
			(at 203.2 55.88 0)
			(effects
				(font
					(size 1.27 1.27)
				)
				(justify left bottom)
				(hide yes)
			)
		)
		(pin "1"
		)
		(pin "2"
		)
		(instances
			(project "k410t-devboard"
				(path ""
					(reference "C144")
					(unit 1)
				)
			)
		)
	)
	(symbol
		(lib_id "antmicroCapacitorsmisc:C_100n_0201")
		(at 222.25 220.98 270)
		(mirror x)
		(unit 1)
		(exclude_from_sim no)
		(in_bom yes)
		(on_board yes)
		(dnp no)
		(property "Reference" "C122"
			(at 221.615 216.535 90)
			(effects
				(font
					(size 1.27 1.27)
				)
				(justify right)
			)
		)
		(property "Value" "C_100n_0201"
			(at 212.09 200.66 0)
			(effects
				(font
					(size 1.27 1.27)
					(thickness 0.15)
				)
				(justify left bottom)
				(hide yes)
			)
		)
		(property "Footprint" "antmicro-footprints:C_0201"
			(at 209.55 200.66 0)
			(effects
				(font
					(size 1.27 1.27)
					(thickness 0.15)
				)
				(justify left bottom)
				(hide yes)
			)
		)
		(property "Datasheet" "https://www.yageo.com/en/Chart/Download/pdf/CC0201KRX6S5BB104"
			(at 207.01 200.66 0)
			(effects
				(font
					(size 1.27 1.27)
					(thickness 0.15)
				)
				(justify left bottom)
				(hide yes)
			)
		)
		(property "Description" ""
			(at 222.25 220.98 0)
			(effects
				(font
					(size 1.27 1.27)
				)
			)
		)
		(property "Manufacturer" "YAGEO"
			(at 201.93 200.66 0)
			(effects
				(font
					(size 1.27 1.27)
					(thickness 0.15)
				)
				(justify left bottom)
				(hide yes)
			)
		)
		(property "MPN" "CC0201KRX6S5BB104"
			(at 204.47 200.66 0)
			(effects
				(font
					(size 1.27 1.27)
					(thickness 0.15)
				)
				(justify left bottom)
				(hide yes)
			)
		)
		(property "Val" "100n"
			(at 221.615 220.345 90)
			(effects
				(font
					(size 1.27 1.27)
					(thickness 0.15)
				)
				(justify right)
			)
		)
		(property "License" "Apache-2.0"
			(at 199.39 200.66 0)
			(effects
				(font
					(size 1.27 1.27)
					(thickness 0.15)
				)
				(justify left bottom)
				(hide yes)
			)
		)
		(property "Author" "Antmicro"
			(at 196.85 200.66 0)
			(effects
				(font
					(size 1.27 1.27)
					(thickness 0.15)
				)
				(justify left bottom)
				(hide yes)
			)
		)
		(property "Voltage" ""
			(at 194.31 200.66 0)
			(effects
				(font
					(size 1.27 1.27)
				)
				(justify left bottom)
				(hide yes)
			)
		)
		(property "Dielectric" ""
			(at 191.77 200.66 0)
			(effects
				(font
					(size 1.27 1.27)
				)
				(justify left bottom)
				(hide yes)
			)
		)
		(pin "1"
		)
		(pin "2"
		)
		(instances
			(project "k410t-devboard"
				(path ""
					(reference "C122")
					(unit 1)
				)
			)
		)
	)
	(symbol
		(lib_id "antmicroCapacitorsmisc:C_4u7_0201")
		(at 233.68 53.34 270)
		(mirror x)
		(unit 1)
		(exclude_from_sim no)
		(in_bom yes)
		(on_board yes)
		(dnp no)
		(property "Reference" "C110"
			(at 233.045 48.895 90)
			(effects
				(font
					(size 1.27 1.27)
				)
				(justify right)
			)
		)
		(property "Value" "C_4u7_0201"
			(at 223.52 33.02 0)
			(effects
				(font
					(size 1.27 1.27)
					(thickness 0.15)
				)
				(justify left bottom)
				(hide yes)
			)
		)
		(property "Footprint" "antmicro-footprints:C_0201"
			(at 220.98 33.02 0)
			(effects
				(font
					(size 1.27 1.27)
					(thickness 0.15)
				)
				(justify left bottom)
				(hide yes)
			)
		)
		(property "Datasheet" "https://www.murata.com/products/productdetail?partno=GRM035R60J475ME15%23"
			(at 218.44 33.02 0)
			(effects
				(font
					(size 1.27 1.27)
					(thickness 0.15)
				)
				(justify left bottom)
				(hide yes)
			)
		)
		(property "Description" ""
			(at 233.68 53.34 0)
			(effects
				(font
					(size 1.27 1.27)
				)
			)
		)
		(property "Manufacturer" "Murata"
			(at 213.36 33.02 0)
			(effects
				(font
					(size 1.27 1.27)
					(thickness 0.15)
				)
				(justify left bottom)
				(hide yes)
			)
		)
		(property "MPN" "GRM035R60J475ME15D"
			(at 215.9 33.02 0)
			(effects
				(font
					(size 1.27 1.27)
					(thickness 0.15)
				)
				(justify left bottom)
				(hide yes)
			)
		)
		(property "Val" "4u7"
			(at 233.045 52.705 90)
			(effects
				(font
					(size 1.27 1.27)
					(thickness 0.15)
				)
				(justify right)
			)
		)
		(property "License" "Apache-2.0"
			(at 210.82 33.02 0)
			(effects
				(font
					(size 1.27 1.27)
					(thickness 0.15)
				)
				(justify left bottom)
				(hide yes)
			)
		)
		(property "Author" "Antmicro"
			(at 208.28 33.02 0)
			(effects
				(font
					(size 1.27 1.27)
					(thickness 0.15)
				)
				(justify left bottom)
				(hide yes)
			)
		)
		(property "Voltage" ""
			(at 205.74 33.02 0)
			(effects
				(font
					(size 1.27 1.27)
				)
				(justify left bottom)
				(hide yes)
			)
		)
		(property "Dielectric" ""
			(at 203.2 33.02 0)
			(effects
				(font
					(size 1.27 1.27)
				)
				(justify left bottom)
				(hide yes)
			)
		)
		(pin "1"
		)
		(pin "2"
		)
		(instances
			(project "k410t-devboard"
				(path ""
					(reference "C110")
					(unit 1)
				)
			)
		)
	)
	(symbol
		(lib_id "antmicroCapacitors0402:C_100n_0402")
		(at 210.82 31.75 90)
		(mirror x)
		(unit 1)
		(exclude_from_sim no)
		(in_bom yes)
		(on_board yes)
		(dnp no)
		(property "Reference" "C111"
			(at 211.455 32.385 90)
			(effects
				(font
					(size 1.27 1.27)
				)
				(justify right)
			)
		)
		(property "Value" "C_100n_0402"
			(at 220.98 52.07 0)
			(effects
				(font
					(size 1.27 1.27)
					(thickness 0.15)
				)
				(justify left bottom)
				(hide yes)
			)
		)
		(property "Footprint" "antmicro-footprints:C_0402_1005Metric"
			(at 223.52 52.07 0)
			(effects
				(font
					(size 1.27 1.27)
					(thickness 0.15)
				)
				(justify left bottom)
				(hide yes)
			)
		)
		(property "Datasheet" "https://www.murata.com/products/productdetail?partno=GRM155R61H104KE14%23"
			(at 226.06 52.07 0)
			(effects
				(font
					(size 1.27 1.27)
					(thickness 0.15)
				)
				(justify left bottom)
				(hide yes)
			)
		)
		(property "Description" ""
			(at 210.82 31.75 0)
			(effects
				(font
					(size 1.27 1.27)
				)
			)
		)
		(property "Manufacturer" "Murata"
			(at 231.14 52.07 0)
			(effects
				(font
					(size 1.27 1.27)
					(thickness 0.15)
				)
				(justify left bottom)
				(hide yes)
			)
		)
		(property "MPN" "GRM155R61H104KE14D"
			(at 228.6 52.07 0)
			(effects
				(font
					(size 1.27 1.27)
					(thickness 0.15)
				)
				(justify left bottom)
				(hide yes)
			)
		)
		(property "Val" "100n"
			(at 211.455 36.195 90)
			(effects
				(font
					(size 1.27 1.27)
					(thickness 0.15)
				)
				(justify right)
			)
		)
		(property "License" "Apache-2.0"
			(at 233.68 52.07 0)
			(effects
				(font
					(size 1.27 1.27)
					(thickness 0.15)
				)
				(justify left bottom)
				(hide yes)
			)
		)
		(property "Author" "Antmicro"
			(at 236.22 52.07 0)
			(effects
				(font
					(size 1.27 1.27)
					(thickness 0.15)
				)
				(justify left bottom)
				(hide yes)
			)
		)
		(property "Voltage" "50V"
			(at 238.76 52.07 0)
			(effects
				(font
					(size 1.27 1.27)
				)
				(justify left bottom)
				(hide yes)
			)
		)
		(property "Dielectric" "X5R"
			(at 241.3 52.07 0)
			(effects
				(font
					(size 1.27 1.27)
				)
				(justify left bottom)
				(hide yes)
			)
		)
		(pin "1"
		)
		(pin "2"
		)
		(instances
			(project "k410t-devboard"
				(path ""
					(reference "C111")
					(unit 1)
				)
			)
		)
	)
	(symbol
		(lib_id "antmicroCapacitors0603:C_47u_0603")
		(at 149.86 31.75 90)
		(mirror x)
		(unit 1)
		(exclude_from_sim no)
		(in_bom yes)
		(on_board yes)
		(dnp no)
		(property "Reference" "C112"
			(at 150.495 32.385 90)
			(effects
				(font
					(size 1.27 1.27)
				)
				(justify right)
			)
		)
		(property "Value" "C_47u_0603"
			(at 160.02 52.07 0)
			(effects
				(font
					(size 1.27 1.27)
					(thickness 0.15)
				)
				(justify left bottom)
				(hide yes)
			)
		)
		(property "Footprint" "antmicro-footprints:C_0603_1608Metric"
			(at 162.56 52.07 0)
			(effects
				(font
					(size 1.27 1.27)
					(thickness 0.15)
				)
				(justify left bottom)
				(hide yes)
			)
		)
		(property "Datasheet" "https://www.murata.com/products/productdetail?partno=GRM188R60J476ME15%23"
			(at 165.1 52.07 0)
			(effects
				(font
					(size 1.27 1.27)
					(thickness 0.15)
				)
				(justify left bottom)
				(hide yes)
			)
		)
		(property "Description" ""
			(at 149.86 31.75 0)
			(effects
				(font
					(size 1.27 1.27)
				)
			)
		)
		(property "Manufacturer" "Murata"
			(at 170.18 52.07 0)
			(effects
				(font
					(size 1.27 1.27)
					(thickness 0.15)
				)
				(justify left bottom)
				(hide yes)
			)
		)
		(property "MPN" "GRM188R60J476ME15D"
			(at 167.64 52.07 0)
			(effects
				(font
					(size 1.27 1.27)
					(thickness 0.15)
				)
				(justify left bottom)
				(hide yes)
			)
		)
		(property "Val" "47u"
			(at 150.495 36.195 90)
			(effects
				(font
					(size 1.27 1.27)
					(thickness 0.15)
				)
				(justify right)
			)
		)
		(property "License" "Apache-2.0"
			(at 172.72 52.07 0)
			(effects
				(font
					(size 1.27 1.27)
					(thickness 0.15)
				)
				(justify left bottom)
				(hide yes)
			)
		)
		(property "Author" "Antmicro"
			(at 175.26 52.07 0)
			(effects
				(font
					(size 1.27 1.27)
					(thickness 0.15)
				)
				(justify left bottom)
				(hide yes)
			)
		)
		(property "Voltage" ""
			(at 177.8 52.07 0)
			(effects
				(font
					(size 1.27 1.27)
				)
				(justify left bottom)
				(hide yes)
			)
		)
		(property "Dielectric" ""
			(at 180.34 52.07 0)
			(effects
				(font
					(size 1.27 1.27)
				)
				(justify left bottom)
				(hide yes)
			)
		)
		(pin "1"
		)
		(pin "2"
		)
		(instances
			(project "k410t-devboard"
				(path ""
					(reference "C112")
					(unit 1)
				)
			)
		)
	)
	(symbol
		(lib_id "antmicroCapacitors0402:C_100n_0402")
		(at 218.44 93.98 90)
		(unit 1)
		(exclude_from_sim no)
		(in_bom yes)
		(on_board yes)
		(dnp no)
		(property "Reference" "C155"
			(at 219.075 89.535 90)
			(effects
				(font
					(size 1.27 1.27)
				)
				(justify right)
			)
		)
		(property "Value" "C_100n_0402"
			(at 228.6 73.66 0)
			(effects
				(font
					(size 1.27 1.27)
					(thickness 0.15)
				)
				(justify left bottom)
				(hide yes)
			)
		)
		(property "Footprint" "antmicro-footprints:C_0402_1005Metric"
			(at 231.14 73.66 0)
			(effects
				(font
					(size 1.27 1.27)
					(thickness 0.15)
				)
				(justify left bottom)
				(hide yes)
			)
		)
		(property "Datasheet" "https://www.murata.com/products/productdetail?partno=GRM155R61H104KE14%23"
			(at 233.68 73.66 0)
			(effects
				(font
					(size 1.27 1.27)
					(thickness 0.15)
				)
				(justify left bottom)
				(hide yes)
			)
		)
		(property "Description" ""
			(at 218.44 93.98 0)
			(effects
				(font
					(size 1.27 1.27)
				)
			)
		)
		(property "Manufacturer" "Murata"
			(at 238.76 73.66 0)
			(effects
				(font
					(size 1.27 1.27)
					(thickness 0.15)
				)
				(justify left bottom)
				(hide yes)
			)
		)
		(property "MPN" "GRM155R61H104KE14D"
			(at 236.22 73.66 0)
			(effects
				(font
					(size 1.27 1.27)
					(thickness 0.15)
				)
				(justify left bottom)
				(hide yes)
			)
		)
		(property "Val" "100n"
			(at 219.075 93.345 90)
			(effects
				(font
					(size 1.27 1.27)
					(thickness 0.15)
				)
				(justify right)
			)
		)
		(property "License" "Apache-2.0"
			(at 241.3 73.66 0)
			(effects
				(font
					(size 1.27 1.27)
					(thickness 0.15)
				)
				(justify left bottom)
				(hide yes)
			)
		)
		(property "Author" "Antmicro"
			(at 243.84 73.66 0)
			(effects
				(font
					(size 1.27 1.27)
					(thickness 0.15)
				)
				(justify left bottom)
				(hide yes)
			)
		)
		(property "Voltage" "50V"
			(at 246.38 73.66 0)
			(effects
				(font
					(size 1.27 1.27)
				)
				(justify left bottom)
				(hide yes)
			)
		)
		(property "Dielectric" "X5R"
			(at 248.92 73.66 0)
			(effects
				(font
					(size 1.27 1.27)
				)
				(justify left bottom)
				(hide yes)
			)
		)
		(pin "1"
		)
		(pin "2"
		)
		(instances
			(project "k410t-devboard"
				(path ""
					(reference "C155")
					(unit 1)
				)
			)
		)
	)
	(symbol
		(lib_id "antmicroCapacitorsmisc:C_100n_0201")
		(at 180.34 76.2 90)
		(unit 1)
		(exclude_from_sim no)
		(in_bom yes)
		(on_board yes)
		(dnp no)
		(property "Reference" "C146"
			(at 180.975 71.755 90)
			(effects
				(font
					(size 1.27 1.27)
				)
				(justify right)
			)
		)
		(property "Value" "C_100n_0201"
			(at 190.5 55.88 0)
			(effects
				(font
					(size 1.27 1.27)
					(thickness 0.15)
				)
				(justify left bottom)
				(hide yes)
			)
		)
		(property "Footprint" "antmicro-footprints:C_0201"
			(at 193.04 55.88 0)
			(effects
				(font
					(size 1.27 1.27)
					(thickness 0.15)
				)
				(justify left bottom)
				(hide yes)
			)
		)
		(property "Datasheet" "https://www.yageo.com/en/Chart/Download/pdf/CC0201KRX6S5BB104"
			(at 195.58 55.88 0)
			(effects
				(font
					(size 1.27 1.27)
					(thickness 0.15)
				)
				(justify left bottom)
				(hide yes)
			)
		)
		(property "Description" ""
			(at 180.34 76.2 0)
			(effects
				(font
					(size 1.27 1.27)
				)
			)
		)
		(property "Manufacturer" "YAGEO"
			(at 200.66 55.88 0)
			(effects
				(font
					(size 1.27 1.27)
					(thickness 0.15)
				)
				(justify left bottom)
				(hide yes)
			)
		)
		(property "MPN" "CC0201KRX6S5BB104"
			(at 198.12 55.88 0)
			(effects
				(font
					(size 1.27 1.27)
					(thickness 0.15)
				)
				(justify left bottom)
				(hide yes)
			)
		)
		(property "Val" "100n"
			(at 180.975 75.565 90)
			(effects
				(font
					(size 1.27 1.27)
					(thickness 0.15)
				)
				(justify right)
			)
		)
		(property "License" "Apache-2.0"
			(at 203.2 55.88 0)
			(effects
				(font
					(size 1.27 1.27)
					(thickness 0.15)
				)
				(justify left bottom)
				(hide yes)
			)
		)
		(property "Author" "Antmicro"
			(at 205.74 55.88 0)
			(effects
				(font
					(size 1.27 1.27)
					(thickness 0.15)
				)
				(justify left bottom)
				(hide yes)
			)
		)
		(property "Voltage" ""
			(at 208.28 55.88 0)
			(effects
				(font
					(size 1.27 1.27)
				)
				(justify left bottom)
				(hide yes)
			)
		)
		(property "Dielectric" ""
			(at 210.82 55.88 0)
			(effects
				(font
					(size 1.27 1.27)
				)
				(justify left bottom)
				(hide yes)
			)
		)
		(pin "1"
		)
		(pin "2"
		)
		(instances
			(project "k410t-devboard"
				(path ""
					(reference "C146")
					(unit 1)
				)
			)
		)
	)
	(symbol
		(lib_id "antmicroCapacitors0402:C_100n_0402")
		(at 229.87 238.76 270)
		(mirror x)
		(unit 1)
		(exclude_from_sim no)
		(in_bom yes)
		(on_board yes)
		(dnp no)
		(property "Reference" "C116"
			(at 229.235 234.315 90)
			(effects
				(font
					(size 1.27 1.27)
				)
				(justify right)
			)
		)
		(property "Value" "C_100n_0402"
			(at 219.71 218.44 0)
			(effects
				(font
					(size 1.27 1.27)
					(thickness 0.15)
				)
				(justify left bottom)
				(hide yes)
			)
		)
		(property "Footprint" "antmicro-footprints:C_0402_1005Metric"
			(at 217.17 218.44 0)
			(effects
				(font
					(size 1.27 1.27)
					(thickness 0.15)
				)
				(justify left bottom)
				(hide yes)
			)
		)
		(property "Datasheet" "https://www.murata.com/products/productdetail?partno=GRM155R61H104KE14%23"
			(at 214.63 218.44 0)
			(effects
				(font
					(size 1.27 1.27)
					(thickness 0.15)
				)
				(justify left bottom)
				(hide yes)
			)
		)
		(property "Description" ""
			(at 229.87 238.76 0)
			(effects
				(font
					(size 1.27 1.27)
				)
			)
		)
		(property "Manufacturer" "Murata"
			(at 209.55 218.44 0)
			(effects
				(font
					(size 1.27 1.27)
					(thickness 0.15)
				)
				(justify left bottom)
				(hide yes)
			)
		)
		(property "MPN" "GRM155R61H104KE14D"
			(at 212.09 218.44 0)
			(effects
				(font
					(size 1.27 1.27)
					(thickness 0.15)
				)
				(justify left bottom)
				(hide yes)
			)
		)
		(property "Val" "100n"
			(at 229.235 238.125 90)
			(effects
				(font
					(size 1.27 1.27)
					(thickness 0.15)
				)
				(justify right)
			)
		)
		(property "License" "Apache-2.0"
			(at 207.01 218.44 0)
			(effects
				(font
					(size 1.27 1.27)
					(thickness 0.15)
				)
				(justify left bottom)
				(hide yes)
			)
		)
		(property "Author" "Antmicro"
			(at 204.47 218.44 0)
			(effects
				(font
					(size 1.27 1.27)
					(thickness 0.15)
				)
				(justify left bottom)
				(hide yes)
			)
		)
		(property "Voltage" "50V"
			(at 201.93 218.44 0)
			(effects
				(font
					(size 1.27 1.27)
				)
				(justify left bottom)
				(hide yes)
			)
		)
		(property "Dielectric" "X5R"
			(at 199.39 218.44 0)
			(effects
				(font
					(size 1.27 1.27)
				)
				(justify left bottom)
				(hide yes)
			)
		)
		(pin "1"
		)
		(pin "2"
		)
		(instances
			(project "k410t-devboard"
				(path ""
					(reference "C116")
					(unit 1)
				)
			)
		)
	)
	(symbol
		(lib_id "antmicroCapacitors0402:C_100n_0402")
		(at 222.25 238.76 270)
		(mirror x)
		(unit 1)
		(exclude_from_sim no)
		(in_bom yes)
		(on_board yes)
		(dnp no)
		(property "Reference" "C121"
			(at 221.615 234.315 90)
			(effects
				(font
					(size 1.27 1.27)
				)
				(justify right)
			)
		)
		(property "Value" "C_100n_0402"
			(at 212.09 218.44 0)
			(effects
				(font
					(size 1.27 1.27)
					(thickness 0.15)
				)
				(justify left bottom)
				(hide yes)
			)
		)
		(property "Footprint" "antmicro-footprints:C_0402_1005Metric"
			(at 209.55 218.44 0)
			(effects
				(font
					(size 1.27 1.27)
					(thickness 0.15)
				)
				(justify left bottom)
				(hide yes)
			)
		)
		(property "Datasheet" "https://www.murata.com/products/productdetail?partno=GRM155R61H104KE14%23"
			(at 207.01 218.44 0)
			(effects
				(font
					(size 1.27 1.27)
					(thickness 0.15)
				)
				(justify left bottom)
				(hide yes)
			)
		)
		(property "Description" ""
			(at 222.25 238.76 0)
			(effects
				(font
					(size 1.27 1.27)
				)
			)
		)
		(property "Manufacturer" "Murata"
			(at 201.93 218.44 0)
			(effects
				(font
					(size 1.27 1.27)
					(thickness 0.15)
				)
				(justify left bottom)
				(hide yes)
			)
		)
		(property "MPN" "GRM155R61H104KE14D"
			(at 204.47 218.44 0)
			(effects
				(font
					(size 1.27 1.27)
					(thickness 0.15)
				)
				(justify left bottom)
				(hide yes)
			)
		)
		(property "Val" "100n"
			(at 221.615 238.125 90)
			(effects
				(font
					(size 1.27 1.27)
					(thickness 0.15)
				)
				(justify right)
			)
		)
		(property "License" "Apache-2.0"
			(at 199.39 218.44 0)
			(effects
				(font
					(size 1.27 1.27)
					(thickness 0.15)
				)
				(justify left bottom)
				(hide yes)
			)
		)
		(property "Author" "Antmicro"
			(at 196.85 218.44 0)
			(effects
				(font
					(size 1.27 1.27)
					(thickness 0.15)
				)
				(justify left bottom)
				(hide yes)
			)
		)
		(property "Voltage" "50V"
			(at 194.31 218.44 0)
			(effects
				(font
					(size 1.27 1.27)
				)
				(justify left bottom)
				(hide yes)
			)
		)
		(property "Dielectric" "X5R"
			(at 191.77 218.44 0)
			(effects
				(font
					(size 1.27 1.27)
				)
				(justify left bottom)
				(hide yes)
			)
		)
		(pin "1"
		)
		(pin "2"
		)
		(instances
			(project "k410t-devboard"
				(path ""
					(reference "C121")
					(unit 1)
				)
			)
		)
	)
	(symbol
		(lib_id "antmicroCapacitorsmisc:C_4u7_0201")
		(at 176.53 201.93 270)
		(mirror x)
		(unit 1)
		(exclude_from_sim no)
		(in_bom yes)
		(on_board yes)
		(dnp no)
		(property "Reference" "C34"
			(at 175.895 197.485 90)
			(effects
				(font
					(size 1.27 1.27)
				)
				(justify right)
			)
		)
		(property "Value" "C_4u7_0201"
			(at 166.37 181.61 0)
			(effects
				(font
					(size 1.27 1.27)
					(thickness 0.15)
				)
				(justify left bottom)
				(hide yes)
			)
		)
		(property "Footprint" "antmicro-footprints:C_0201"
			(at 163.83 181.61 0)
			(effects
				(font
					(size 1.27 1.27)
					(thickness 0.15)
				)
				(justify left bottom)
				(hide yes)
			)
		)
		(property "Datasheet" "https://www.murata.com/products/productdetail?partno=GRM035R60J475ME15%23"
			(at 161.29 181.61 0)
			(effects
				(font
					(size 1.27 1.27)
					(thickness 0.15)
				)
				(justify left bottom)
				(hide yes)
			)
		)
		(property "Description" ""
			(at 176.53 201.93 0)
			(effects
				(font
					(size 1.27 1.27)
				)
			)
		)
		(property "Manufacturer" "Murata"
			(at 156.21 181.61 0)
			(effects
				(font
					(size 1.27 1.27)
					(thickness 0.15)
				)
				(justify left bottom)
				(hide yes)
			)
		)
		(property "MPN" "GRM035R60J475ME15D"
			(at 158.75 181.61 0)
			(effects
				(font
					(size 1.27 1.27)
					(thickness 0.15)
				)
				(justify left bottom)
				(hide yes)
			)
		)
		(property "Val" "4u7"
			(at 175.895 201.295 90)
			(effects
				(font
					(size 1.27 1.27)
					(thickness 0.15)
				)
				(justify right)
			)
		)
		(property "License" "Apache-2.0"
			(at 153.67 181.61 0)
			(effects
				(font
					(size 1.27 1.27)
					(thickness 0.15)
				)
				(justify left bottom)
				(hide yes)
			)
		)
		(property "Author" "Antmicro"
			(at 151.13 181.61 0)
			(effects
				(font
					(size 1.27 1.27)
					(thickness 0.15)
				)
				(justify left bottom)
				(hide yes)
			)
		)
		(property "Voltage" ""
			(at 148.59 181.61 0)
			(effects
				(font
					(size 1.27 1.27)
				)
				(justify left bottom)
				(hide yes)
			)
		)
		(property "Dielectric" ""
			(at 146.05 181.61 0)
			(effects
				(font
					(size 1.27 1.27)
				)
				(justify left bottom)
				(hide yes)
			)
		)
		(pin "1"
		)
		(pin "2"
		)
		(instances
			(project "k410t-devboard"
				(path ""
					(reference "C34")
					(unit 1)
				)
			)
		)
	)
	(symbol
		(lib_id "antmicropower:GND")
		(at 149.86 97.79 0)
		(unit 1)
		(exclude_from_sim no)
		(in_bom yes)
		(on_board yes)
		(dnp no)
		(property "Reference" "#PWR0495"
			(at 149.86 104.14 0)
			(effects
				(font
					(size 1.27 1.27)
				)
				(hide yes)
			)
		)
		(property "Value" "GND"
			(at 149.86 101.6 0)
			(effects
				(font
					(size 1.27 1.27)
				)
			)
		)
		(property "Footprint" ""
			(at 158.75 105.41 0)
			(effects
				(font
					(size 1.27 1.27)
					(thickness 0.15)
				)
				(justify left bottom)
				(hide yes)
			)
		)
		(property "Datasheet" ""
			(at 158.75 110.49 0)
			(effects
				(font
					(size 1.27 1.27)
					(thickness 0.15)
				)
				(justify left bottom)
				(hide yes)
			)
		)
		(property "Description" ""
			(at 149.86 97.79 0)
			(effects
				(font
					(size 1.27 1.27)
				)
			)
		)
		(property "Author" "Antmicro"
			(at 158.75 105.41 0)
			(effects
				(font
					(size 1.27 1.27)
					(thickness 0.15)
				)
				(justify left bottom)
				(hide yes)
			)
		)
		(property "License" "Apache-2.0"
			(at 158.75 107.95 0)
			(effects
				(font
					(size 1.27 1.27)
					(thickness 0.15)
				)
				(justify left bottom)
				(hide yes)
			)
		)
		(pin "1"
		)
		(instances
			(project "k410t-devboard"
				(path ""
					(reference "#PWR0495")
					(unit 1)
				)
			)
		)
	)
	(symbol
		(lib_id "antmicroCapacitors0603:C_47u_0603")
		(at 214.63 168.91 90)
		(unit 1)
		(exclude_from_sim no)
		(in_bom yes)
		(on_board yes)
		(dnp no)
		(property "Reference" "C54"
			(at 215.265 164.465 90)
			(effects
				(font
					(size 1.27 1.27)
				)
				(justify right)
			)
		)
		(property "Value" "C_47u_0603"
			(at 224.79 148.59 0)
			(effects
				(font
					(size 1.27 1.27)
					(thickness 0.15)
				)
				(justify left bottom)
				(hide yes)
			)
		)
		(property "Footprint" "antmicro-footprints:C_0603_1608Metric"
			(at 227.33 148.59 0)
			(effects
				(font
					(size 1.27 1.27)
					(thickness 0.15)
				)
				(justify left bottom)
				(hide yes)
			)
		)
		(property "Datasheet" "https://www.murata.com/products/productdetail?partno=GRM188R60J476ME15%23"
			(at 229.87 148.59 0)
			(effects
				(font
					(size 1.27 1.27)
					(thickness 0.15)
				)
				(justify left bottom)
				(hide yes)
			)
		)
		(property "Description" ""
			(at 214.63 168.91 0)
			(effects
				(font
					(size 1.27 1.27)
				)
			)
		)
		(property "Manufacturer" "Murata"
			(at 234.95 148.59 0)
			(effects
				(font
					(size 1.27 1.27)
					(thickness 0.15)
				)
				(justify left bottom)
				(hide yes)
			)
		)
		(property "MPN" "GRM188R60J476ME15D"
			(at 232.41 148.59 0)
			(effects
				(font
					(size 1.27 1.27)
					(thickness 0.15)
				)
				(justify left bottom)
				(hide yes)
			)
		)
		(property "Val" "47u"
			(at 215.265 168.275 90)
			(effects
				(font
					(size 1.27 1.27)
					(thickness 0.15)
				)
				(justify right)
			)
		)
		(property "License" "Apache-2.0"
			(at 237.49 148.59 0)
			(effects
				(font
					(size 1.27 1.27)
					(thickness 0.15)
				)
				(justify left bottom)
				(hide yes)
			)
		)
		(property "Author" "Antmicro"
			(at 240.03 148.59 0)
			(effects
				(font
					(size 1.27 1.27)
					(thickness 0.15)
				)
				(justify left bottom)
				(hide yes)
			)
		)
		(property "Voltage" ""
			(at 242.57 148.59 0)
			(effects
				(font
					(size 1.27 1.27)
				)
				(justify left bottom)
				(hide yes)
			)
		)
		(property "Dielectric" ""
			(at 245.11 148.59 0)
			(effects
				(font
					(size 1.27 1.27)
				)
				(justify left bottom)
				(hide yes)
			)
		)
		(pin "1"
		)
		(pin "2"
		)
		(instances
			(project "k410t-devboard"
				(path ""
					(reference "C54")
					(unit 1)
				)
			)
		)
	)
	(symbol
		(lib_id "antmicroCapacitors0402:C_100n_0402")
		(at 199.39 238.76 270)
		(mirror x)
		(unit 1)
		(exclude_from_sim no)
		(in_bom yes)
		(on_board yes)
		(dnp no)
		(property "Reference" "C131"
			(at 198.755 234.315 90)
			(effects
				(font
					(size 1.27 1.27)
				)
				(justify right)
			)
		)
		(property "Value" "C_100n_0402"
			(at 189.23 218.44 0)
			(effects
				(font
					(size 1.27 1.27)
					(thickness 0.15)
				)
				(justify left bottom)
				(hide yes)
			)
		)
		(property "Footprint" "antmicro-footprints:C_0402_1005Metric"
			(at 186.69 218.44 0)
			(effects
				(font
					(size 1.27 1.27)
					(thickness 0.15)
				)
				(justify left bottom)
				(hide yes)
			)
		)
		(property "Datasheet" "https://www.murata.com/products/productdetail?partno=GRM155R61H104KE14%23"
			(at 184.15 218.44 0)
			(effects
				(font
					(size 1.27 1.27)
					(thickness 0.15)
				)
				(justify left bottom)
				(hide yes)
			)
		)
		(property "Description" ""
			(at 199.39 238.76 0)
			(effects
				(font
					(size 1.27 1.27)
				)
			)
		)
		(property "Manufacturer" "Murata"
			(at 179.07 218.44 0)
			(effects
				(font
					(size 1.27 1.27)
					(thickness 0.15)
				)
				(justify left bottom)
				(hide yes)
			)
		)
		(property "MPN" "GRM155R61H104KE14D"
			(at 181.61 218.44 0)
			(effects
				(font
					(size 1.27 1.27)
					(thickness 0.15)
				)
				(justify left bottom)
				(hide yes)
			)
		)
		(property "Val" "100n"
			(at 198.755 238.125 90)
			(effects
				(font
					(size 1.27 1.27)
					(thickness 0.15)
				)
				(justify right)
			)
		)
		(property "License" "Apache-2.0"
			(at 176.53 218.44 0)
			(effects
				(font
					(size 1.27 1.27)
					(thickness 0.15)
				)
				(justify left bottom)
				(hide yes)
			)
		)
		(property "Author" "Antmicro"
			(at 173.99 218.44 0)
			(effects
				(font
					(size 1.27 1.27)
					(thickness 0.15)
				)
				(justify left bottom)
				(hide yes)
			)
		)
		(property "Voltage" "50V"
			(at 171.45 218.44 0)
			(effects
				(font
					(size 1.27 1.27)
				)
				(justify left bottom)
				(hide yes)
			)
		)
		(property "Dielectric" "X5R"
			(at 168.91 218.44 0)
			(effects
				(font
					(size 1.27 1.27)
				)
				(justify left bottom)
				(hide yes)
			)
		)
		(pin "1"
		)
		(pin "2"
		)
		(instances
			(project "k410t-devboard"
				(path ""
					(reference "C131")
					(unit 1)
				)
			)
		)
	)
	(symbol
		(lib_id "antmicropower:+1V2")
		(at 360.68 243.84 0)
		(mirror y)
		(unit 1)
		(exclude_from_sim no)
		(in_bom yes)
		(on_board yes)
		(dnp no)
		(property "Reference" "#PWR0431"
			(at 360.68 247.65 0)
			(effects
				(font
					(size 1.27 1.27)
				)
				(hide yes)
			)
		)
		(property "Value" "+1V2"
			(at 360.68 240.284 0)
			(effects
				(font
					(size 1.27 1.27)
				)
			)
		)
		(property "Footprint" ""
			(at 360.68 243.84 0)
			(effects
				(font
					(size 1.27 1.27)
				)
				(hide yes)
			)
		)
		(property "Datasheet" ""
			(at 360.68 243.84 0)
			(effects
				(font
					(size 1.27 1.27)
				)
				(hide yes)
			)
		)
		(property "Description" ""
			(at 360.68 243.84 0)
			(effects
				(font
					(size 1.27 1.27)
				)
			)
		)
		(pin "1"
		)
		(instances
			(project "k410t-devboard"
				(path ""
					(reference "#PWR0431")
					(unit 1)
				)
			)
		)
	)
	(symbol
		(lib_id "antmicroCapacitorsmisc:C_100n_0201")
		(at 214.63 238.76 270)
		(mirror x)
		(unit 1)
		(exclude_from_sim no)
		(in_bom yes)
		(on_board yes)
		(dnp no)
		(property "Reference" "C126"
			(at 213.995 234.315 90)
			(effects
				(font
					(size 1.27 1.27)
				)
				(justify right)
			)
		)
		(property "Value" "C_100n_0201"
			(at 204.47 218.44 0)
			(effects
				(font
					(size 1.27 1.27)
					(thickness 0.15)
				)
				(justify left bottom)
				(hide yes)
			)
		)
		(property "Footprint" "antmicro-footprints:C_0201"
			(at 201.93 218.44 0)
			(effects
				(font
					(size 1.27 1.27)
					(thickness 0.15)
				)
				(justify left bottom)
				(hide yes)
			)
		)
		(property "Datasheet" "https://www.yageo.com/en/Chart/Download/pdf/CC0201KRX6S5BB104"
			(at 199.39 218.44 0)
			(effects
				(font
					(size 1.27 1.27)
					(thickness 0.15)
				)
				(justify left bottom)
				(hide yes)
			)
		)
		(property "Description" ""
			(at 214.63 238.76 0)
			(effects
				(font
					(size 1.27 1.27)
				)
			)
		)
		(property "Manufacturer" "YAGEO"
			(at 194.31 218.44 0)
			(effects
				(font
					(size 1.27 1.27)
					(thickness 0.15)
				)
				(justify left bottom)
				(hide yes)
			)
		)
		(property "MPN" "CC0201KRX6S5BB104"
			(at 196.85 218.44 0)
			(effects
				(font
					(size 1.27 1.27)
					(thickness 0.15)
				)
				(justify left bottom)
				(hide yes)
			)
		)
		(property "Val" "100n"
			(at 213.995 238.125 90)
			(effects
				(font
					(size 1.27 1.27)
					(thickness 0.15)
				)
				(justify right)
			)
		)
		(property "License" "Apache-2.0"
			(at 191.77 218.44 0)
			(effects
				(font
					(size 1.27 1.27)
					(thickness 0.15)
				)
				(justify left bottom)
				(hide yes)
			)
		)
		(property "Author" "Antmicro"
			(at 189.23 218.44 0)
			(effects
				(font
					(size 1.27 1.27)
					(thickness 0.15)
				)
				(justify left bottom)
				(hide yes)
			)
		)
		(property "Voltage" ""
			(at 186.69 218.44 0)
			(effects
				(font
					(size 1.27 1.27)
				)
				(justify left bottom)
				(hide yes)
			)
		)
		(property "Dielectric" ""
			(at 184.15 218.44 0)
			(effects
				(font
					(size 1.27 1.27)
				)
				(justify left bottom)
				(hide yes)
			)
		)
		(pin "1"
		)
		(pin "2"
		)
		(instances
			(project "k410t-devboard"
				(path ""
					(reference "C126")
					(unit 1)
				)
			)
		)
	)
	(symbol
		(lib_id "antmicroCapacitorsmisc:C_100n_0201")
		(at 199.39 220.98 270)
		(mirror x)
		(unit 1)
		(exclude_from_sim no)
		(in_bom yes)
		(on_board yes)
		(dnp no)
		(property "Reference" "C132"
			(at 198.755 216.535 90)
			(effects
				(font
					(size 1.27 1.27)
				)
				(justify right)
			)
		)
		(property "Value" "C_100n_0201"
			(at 189.23 200.66 0)
			(effects
				(font
					(size 1.27 1.27)
					(thickness 0.15)
				)
				(justify left bottom)
				(hide yes)
			)
		)
		(property "Footprint" "antmicro-footprints:C_0201"
			(at 186.69 200.66 0)
			(effects
				(font
					(size 1.27 1.27)
					(thickness 0.15)
				)
				(justify left bottom)
				(hide yes)
			)
		)
		(property "Datasheet" "https://www.yageo.com/en/Chart/Download/pdf/CC0201KRX6S5BB104"
			(at 184.15 200.66 0)
			(effects
				(font
					(size 1.27 1.27)
					(thickness 0.15)
				)
				(justify left bottom)
				(hide yes)
			)
		)
		(property "Description" ""
			(at 199.39 220.98 0)
			(effects
				(font
					(size 1.27 1.27)
				)
			)
		)
		(property "Manufacturer" "YAGEO"
			(at 179.07 200.66 0)
			(effects
				(font
					(size 1.27 1.27)
					(thickness 0.15)
				)
				(justify left bottom)
				(hide yes)
			)
		)
		(property "MPN" "CC0201KRX6S5BB104"
			(at 181.61 200.66 0)
			(effects
				(font
					(size 1.27 1.27)
					(thickness 0.15)
				)
				(justify left bottom)
				(hide yes)
			)
		)
		(property "Val" "100n"
			(at 198.755 220.345 90)
			(effects
				(font
					(size 1.27 1.27)
					(thickness 0.15)
				)
				(justify right)
			)
		)
		(property "License" "Apache-2.0"
			(at 176.53 200.66 0)
			(effects
				(font
					(size 1.27 1.27)
					(thickness 0.15)
				)
				(justify left bottom)
				(hide yes)
			)
		)
		(property "Author" "Antmicro"
			(at 173.99 200.66 0)
			(effects
				(font
					(size 1.27 1.27)
					(thickness 0.15)
				)
				(justify left bottom)
				(hide yes)
			)
		)
		(property "Voltage" ""
			(at 171.45 200.66 0)
			(effects
				(font
					(size 1.27 1.27)
				)
				(justify left bottom)
				(hide yes)
			)
		)
		(property "Dielectric" ""
			(at 168.91 200.66 0)
			(effects
				(font
					(size 1.27 1.27)
				)
				(justify left bottom)
				(hide yes)
			)
		)
		(pin "1"
		)
		(pin "2"
		)
		(instances
			(project "k410t-devboard"
				(path ""
					(reference "C132")
					(unit 1)
				)
			)
		)
	)
	(symbol
		(lib_id "antmicropower:+3.3V")
		(at 367.03 238.76 0)
		(mirror y)
		(unit 1)
		(exclude_from_sim no)
		(in_bom yes)
		(on_board yes)
		(dnp no)
		(property "Reference" "#PWR0435"
			(at 367.03 242.57 0)
			(effects
				(font
					(size 1.27 1.27)
				)
				(hide yes)
			)
		)
		(property "Value" "+3V3"
			(at 367.03 235.204 0)
			(effects
				(font
					(size 1.27 1.27)
				)
			)
		)
		(property "Footprint" ""
			(at 367.03 238.76 0)
			(effects
				(font
					(size 1.27 1.27)
				)
				(hide yes)
			)
		)
		(property "Datasheet" ""
			(at 367.03 238.76 0)
			(effects
				(font
					(size 1.27 1.27)
				)
				(hide yes)
			)
		)
		(property "Description" ""
			(at 367.03 238.76 0)
			(effects
				(font
					(size 1.27 1.27)
				)
			)
		)
		(pin "1"
		)
		(instances
			(project "k410t-devboard"
				(path ""
					(reference "#PWR0435")
					(unit 1)
				)
			)
		)
	)
	(symbol
		(lib_id "antmicroCapacitorsmisc:C_4u7_0201")
		(at 153.67 201.93 270)
		(mirror x)
		(unit 1)
		(exclude_from_sim no)
		(in_bom yes)
		(on_board yes)
		(dnp no)
		(property "Reference" "C50"
			(at 153.035 197.485 90)
			(effects
				(font
					(size 1.27 1.27)
				)
				(justify right)
			)
		)
		(property "Value" "C_4u7_0201"
			(at 143.51 181.61 0)
			(effects
				(font
					(size 1.27 1.27)
					(thickness 0.15)
				)
				(justify left bottom)
				(hide yes)
			)
		)
		(property "Footprint" "antmicro-footprints:C_0201"
			(at 140.97 181.61 0)
			(effects
				(font
					(size 1.27 1.27)
					(thickness 0.15)
				)
				(justify left bottom)
				(hide yes)
			)
		)
		(property "Datasheet" "https://www.murata.com/products/productdetail?partno=GRM035R60J475ME15%23"
			(at 138.43 181.61 0)
			(effects
				(font
					(size 1.27 1.27)
					(thickness 0.15)
				)
				(justify left bottom)
				(hide yes)
			)
		)
		(property "Description" ""
			(at 153.67 201.93 0)
			(effects
				(font
					(size 1.27 1.27)
				)
			)
		)
		(property "Manufacturer" "Murata"
			(at 133.35 181.61 0)
			(effects
				(font
					(size 1.27 1.27)
					(thickness 0.15)
				)
				(justify left bottom)
				(hide yes)
			)
		)
		(property "MPN" "GRM035R60J475ME15D"
			(at 135.89 181.61 0)
			(effects
				(font
					(size 1.27 1.27)
					(thickness 0.15)
				)
				(justify left bottom)
				(hide yes)
			)
		)
		(property "Val" "4u7"
			(at 153.035 201.295 90)
			(effects
				(font
					(size 1.27 1.27)
					(thickness 0.15)
				)
				(justify right)
			)
		)
		(property "License" "Apache-2.0"
			(at 130.81 181.61 0)
			(effects
				(font
					(size 1.27 1.27)
					(thickness 0.15)
				)
				(justify left bottom)
				(hide yes)
			)
		)
		(property "Author" "Antmicro"
			(at 128.27 181.61 0)
			(effects
				(font
					(size 1.27 1.27)
					(thickness 0.15)
				)
				(justify left bottom)
				(hide yes)
			)
		)
		(property "Voltage" ""
			(at 125.73 181.61 0)
			(effects
				(font
					(size 1.27 1.27)
				)
				(justify left bottom)
				(hide yes)
			)
		)
		(property "Dielectric" ""
			(at 123.19 181.61 0)
			(effects
				(font
					(size 1.27 1.27)
				)
				(justify left bottom)
				(hide yes)
			)
		)
		(pin "1"
		)
		(pin "2"
		)
		(instances
			(project "k410t-devboard"
				(path ""
					(reference "C50")
					(unit 1)
				)
			)
		)
	)
	(symbol
		(lib_id "antmicroCapacitors0603:C_47u_0603")
		(at 146.05 220.98 270)
		(mirror x)
		(unit 1)
		(exclude_from_sim no)
		(in_bom yes)
		(on_board yes)
		(dnp no)
		(property "Reference" "C378"
			(at 145.415 216.535 90)
			(effects
				(font
					(size 1.27 1.27)
				)
				(justify right)
			)
		)
		(property "Value" "C_47u_0603"
			(at 135.89 200.66 0)
			(effects
				(font
					(size 1.27 1.27)
					(thickness 0.15)
				)
				(justify left bottom)
				(hide yes)
			)
		)
		(property "Footprint" "antmicro-footprints:C_0603_1608Metric"
			(at 133.35 200.66 0)
			(effects
				(font
					(size 1.27 1.27)
					(thickness 0.15)
				)
				(justify left bottom)
				(hide yes)
			)
		)
		(property "Datasheet" "https://www.murata.com/products/productdetail?partno=GRM188R60J476ME15%23"
			(at 130.81 200.66 0)
			(effects
				(font
					(size 1.27 1.27)
					(thickness 0.15)
				)
				(justify left bottom)
				(hide yes)
			)
		)
		(property "Description" ""
			(at 146.05 220.98 0)
			(effects
				(font
					(size 1.27 1.27)
				)
			)
		)
		(property "Manufacturer" "Murata"
			(at 125.73 200.66 0)
			(effects
				(font
					(size 1.27 1.27)
					(thickness 0.15)
				)
				(justify left bottom)
				(hide yes)
			)
		)
		(property "MPN" "GRM188R60J476ME15D"
			(at 128.27 200.66 0)
			(effects
				(font
					(size 1.27 1.27)
					(thickness 0.15)
				)
				(justify left bottom)
				(hide yes)
			)
		)
		(property "Val" "47u"
			(at 145.415 220.345 90)
			(effects
				(font
					(size 1.27 1.27)
					(thickness 0.15)
				)
				(justify right)
			)
		)
		(property "License" "Apache-2.0"
			(at 123.19 200.66 0)
			(effects
				(font
					(size 1.27 1.27)
					(thickness 0.15)
				)
				(justify left bottom)
				(hide yes)
			)
		)
		(property "Author" "Antmicro"
			(at 120.65 200.66 0)
			(effects
				(font
					(size 1.27 1.27)
					(thickness 0.15)
				)
				(justify left bottom)
				(hide yes)
			)
		)
		(property "Voltage" ""
			(at 118.11 200.66 0)
			(effects
				(font
					(size 1.27 1.27)
				)
				(justify left bottom)
				(hide yes)
			)
		)
		(property "Dielectric" ""
			(at 115.57 200.66 0)
			(effects
				(font
					(size 1.27 1.27)
				)
				(justify left bottom)
				(hide yes)
			)
		)
		(pin "1"
		)
		(pin "2"
		)
		(instances
			(project "k410t-devboard"
				(path ""
					(reference "C378")
					(unit 1)
				)
			)
		)
	)
	(symbol
		(lib_id "antmicroCapacitorsmisc:C_4u7_0201")
		(at 149.86 93.98 90)
		(unit 1)
		(exclude_from_sim no)
		(in_bom yes)
		(on_board yes)
		(dnp no)
		(property "Reference" "C161"
			(at 150.495 89.535 90)
			(effects
				(font
					(size 1.27 1.27)
				)
				(justify right)
			)
		)
		(property "Value" "C_4u7_0201"
			(at 160.02 73.66 0)
			(effects
				(font
					(size 1.27 1.27)
					(thickness 0.15)
				)
				(justify left bottom)
				(hide yes)
			)
		)
		(property "Footprint" "antmicro-footprints:C_0201"
			(at 162.56 73.66 0)
			(effects
				(font
					(size 1.27 1.27)
					(thickness 0.15)
				)
				(justify left bottom)
				(hide yes)
			)
		)
		(property "Datasheet" "https://www.murata.com/products/productdetail?partno=GRM035R60J475ME15%23"
			(at 165.1 73.66 0)
			(effects
				(font
					(size 1.27 1.27)
					(thickness 0.15)
				)
				(justify left bottom)
				(hide yes)
			)
		)
		(property "Description" ""
			(at 149.86 93.98 0)
			(effects
				(font
					(size 1.27 1.27)
				)
			)
		)
		(property "Manufacturer" "Murata"
			(at 170.18 73.66 0)
			(effects
				(font
					(size 1.27 1.27)
					(thickness 0.15)
				)
				(justify left bottom)
				(hide yes)
			)
		)
		(property "MPN" "GRM035R60J475ME15D"
			(at 167.64 73.66 0)
			(effects
				(font
					(size 1.27 1.27)
					(thickness 0.15)
				)
				(justify left bottom)
				(hide yes)
			)
		)
		(property "Val" "4u7"
			(at 150.495 93.345 90)
			(effects
				(font
					(size 1.27 1.27)
					(thickness 0.15)
				)
				(justify right)
			)
		)
		(property "License" "Apache-2.0"
			(at 172.72 73.66 0)
			(effects
				(font
					(size 1.27 1.27)
					(thickness 0.15)
				)
				(justify left bottom)
				(hide yes)
			)
		)
		(property "Author" "Antmicro"
			(at 175.26 73.66 0)
			(effects
				(font
					(size 1.27 1.27)
					(thickness 0.15)
				)
				(justify left bottom)
				(hide yes)
			)
		)
		(property "Voltage" ""
			(at 177.8 73.66 0)
			(effects
				(font
					(size 1.27 1.27)
				)
				(justify left bottom)
				(hide yes)
			)
		)
		(property "Dielectric" ""
			(at 180.34 73.66 0)
			(effects
				(font
					(size 1.27 1.27)
				)
				(justify left bottom)
				(hide yes)
			)
		)
		(pin "1"
		)
		(pin "2"
		)
		(instances
			(project "k410t-devboard"
				(path ""
					(reference "C161")
					(unit 1)
				)
			)
		)
	)
	(symbol
		(lib_id "antmicropower:+1V0_MGTAVCC")
		(at 139.7 27.94 0)
		(unit 1)
		(exclude_from_sim no)
		(in_bom yes)
		(on_board yes)
		(dnp no)
		(fields_autoplaced yes)
		(property "Reference" "#PWR0439"
			(at 139.7 31.75 0)
			(effects
				(font
					(size 1.27 1.27)
				)
				(hide yes)
			)
		)
		(property "Value" "+1V0_MGTAVCC"
			(at 139.7 24.13 0)
			(effects
				(font
					(size 1.27 1.27)
				)
			)
		)
		(property "Footprint" ""
			(at 139.7 27.94 0)
			(effects
				(font
					(size 1.27 1.27)
				)
				(hide yes)
			)
		)
		(property "Datasheet" ""
			(at 139.7 27.94 0)
			(effects
				(font
					(size 1.27 1.27)
				)
				(hide yes)
			)
		)
		(property "Description" ""
			(at 139.7 27.94 0)
			(effects
				(font
					(size 1.27 1.27)
				)
			)
		)
		(pin "1"
		)
		(instances
			(project "k410t-devboard"
				(path ""
					(reference "#PWR0439")
					(unit 1)
				)
			)
		)
	)
	(symbol
		(lib_id "antmicroCapacitors0402:C_100n_0402")
		(at 207.01 238.76 270)
		(mirror x)
		(unit 1)
		(exclude_from_sim no)
		(in_bom yes)
		(on_board yes)
		(dnp no)
		(property "Reference" "C128"
			(at 206.375 234.315 90)
			(effects
				(font
					(size 1.27 1.27)
				)
				(justify right)
			)
		)
		(property "Value" "C_100n_0402"
			(at 196.85 218.44 0)
			(effects
				(font
					(size 1.27 1.27)
					(thickness 0.15)
				)
				(justify left bottom)
				(hide yes)
			)
		)
		(property "Footprint" "antmicro-footprints:C_0402_1005Metric"
			(at 194.31 218.44 0)
			(effects
				(font
					(size 1.27 1.27)
					(thickness 0.15)
				)
				(justify left bottom)
				(hide yes)
			)
		)
		(property "Datasheet" "https://www.murata.com/products/productdetail?partno=GRM155R61H104KE14%23"
			(at 191.77 218.44 0)
			(effects
				(font
					(size 1.27 1.27)
					(thickness 0.15)
				)
				(justify left bottom)
				(hide yes)
			)
		)
		(property "Description" ""
			(at 207.01 238.76 0)
			(effects
				(font
					(size 1.27 1.27)
				)
			)
		)
		(property "Manufacturer" "Murata"
			(at 186.69 218.44 0)
			(effects
				(font
					(size 1.27 1.27)
					(thickness 0.15)
				)
				(justify left bottom)
				(hide yes)
			)
		)
		(property "MPN" "GRM155R61H104KE14D"
			(at 189.23 218.44 0)
			(effects
				(font
					(size 1.27 1.27)
					(thickness 0.15)
				)
				(justify left bottom)
				(hide yes)
			)
		)
		(property "Val" "100n"
			(at 206.375 238.125 90)
			(effects
				(font
					(size 1.27 1.27)
					(thickness 0.15)
				)
				(justify right)
			)
		)
		(property "License" "Apache-2.0"
			(at 184.15 218.44 0)
			(effects
				(font
					(size 1.27 1.27)
					(thickness 0.15)
				)
				(justify left bottom)
				(hide yes)
			)
		)
		(property "Author" "Antmicro"
			(at 181.61 218.44 0)
			(effects
				(font
					(size 1.27 1.27)
					(thickness 0.15)
				)
				(justify left bottom)
				(hide yes)
			)
		)
		(property "Voltage" "50V"
			(at 179.07 218.44 0)
			(effects
				(font
					(size 1.27 1.27)
				)
				(justify left bottom)
				(hide yes)
			)
		)
		(property "Dielectric" "X5R"
			(at 176.53 218.44 0)
			(effects
				(font
					(size 1.27 1.27)
				)
				(justify left bottom)
				(hide yes)
			)
		)
		(pin "1"
		)
		(pin "2"
		)
		(instances
			(project "k410t-devboard"
				(path ""
					(reference "C128")
					(unit 1)
				)
			)
		)
	)
	(symbol
		(lib_id "antmicroCapacitorsmisc:C_100n_0201")
		(at 233.68 31.75 90)
		(mirror x)
		(unit 1)
		(exclude_from_sim no)
		(in_bom yes)
		(on_board yes)
		(dnp no)
		(property "Reference" "C124"
			(at 234.315 32.385 90)
			(effects
				(font
					(size 1.27 1.27)
				)
				(justify right)
			)
		)
		(property "Value" "C_100n_0201"
			(at 243.84 52.07 0)
			(effects
				(font
					(size 1.27 1.27)
					(thickness 0.15)
				)
				(justify left bottom)
				(hide yes)
			)
		)
		(property "Footprint" "antmicro-footprints:C_0201"
			(at 246.38 52.07 0)
			(effects
				(font
					(size 1.27 1.27)
					(thickness 0.15)
				)
				(justify left bottom)
				(hide yes)
			)
		)
		(property "Datasheet" "https://www.yageo.com/en/Chart/Download/pdf/CC0201KRX6S5BB104"
			(at 248.92 52.07 0)
			(effects
				(font
					(size 1.27 1.27)
					(thickness 0.15)
				)
				(justify left bottom)
				(hide yes)
			)
		)
		(property "Description" ""
			(at 233.68 31.75 0)
			(effects
				(font
					(size 1.27 1.27)
				)
			)
		)
		(property "Manufacturer" "YAGEO"
			(at 254 52.07 0)
			(effects
				(font
					(size 1.27 1.27)
					(thickness 0.15)
				)
				(justify left bottom)
				(hide yes)
			)
		)
		(property "MPN" "CC0201KRX6S5BB104"
			(at 251.46 52.07 0)
			(effects
				(font
					(size 1.27 1.27)
					(thickness 0.15)
				)
				(justify left bottom)
				(hide yes)
			)
		)
		(property "Val" "100n"
			(at 234.315 36.195 90)
			(effects
				(font
					(size 1.27 1.27)
					(thickness 0.15)
				)
				(justify right)
			)
		)
		(property "License" "Apache-2.0"
			(at 256.54 52.07 0)
			(effects
				(font
					(size 1.27 1.27)
					(thickness 0.15)
				)
				(justify left bottom)
				(hide yes)
			)
		)
		(property "Author" "Antmicro"
			(at 259.08 52.07 0)
			(effects
				(font
					(size 1.27 1.27)
					(thickness 0.15)
				)
				(justify left bottom)
				(hide yes)
			)
		)
		(property "Voltage" ""
			(at 261.62 52.07 0)
			(effects
				(font
					(size 1.27 1.27)
				)
				(justify left bottom)
				(hide yes)
			)
		)
		(property "Dielectric" ""
			(at 264.16 52.07 0)
			(effects
				(font
					(size 1.27 1.27)
				)
				(justify left bottom)
				(hide yes)
			)
		)
		(pin "1"
		)
		(pin "2"
		)
		(instances
			(project "k410t-devboard"
				(path ""
					(reference "C124")
					(unit 1)
				)
			)
		)
	)
	(symbol
		(lib_id "antmicroCapacitorsmisc:C_4u7_0201")
		(at 184.15 201.93 270)
		(mirror x)
		(unit 1)
		(exclude_from_sim no)
		(in_bom yes)
		(on_board yes)
		(dnp no)
		(property "Reference" "C28"
			(at 183.515 197.485 90)
			(effects
				(font
					(size 1.27 1.27)
				)
				(justify right)
			)
		)
		(property "Value" "C_4u7_0201"
			(at 173.99 181.61 0)
			(effects
				(font
					(size 1.27 1.27)
					(thickness 0.15)
				)
				(justify left bottom)
				(hide yes)
			)
		)
		(property "Footprint" "antmicro-footprints:C_0201"
			(at 171.45 181.61 0)
			(effects
				(font
					(size 1.27 1.27)
					(thickness 0.15)
				)
				(justify left bottom)
				(hide yes)
			)
		)
		(property "Datasheet" "https://www.murata.com/products/productdetail?partno=GRM035R60J475ME15%23"
			(at 168.91 181.61 0)
			(effects
				(font
					(size 1.27 1.27)
					(thickness 0.15)
				)
				(justify left bottom)
				(hide yes)
			)
		)
		(property "Description" ""
			(at 184.15 201.93 0)
			(effects
				(font
					(size 1.27 1.27)
				)
			)
		)
		(property "Manufacturer" "Murata"
			(at 163.83 181.61 0)
			(effects
				(font
					(size 1.27 1.27)
					(thickness 0.15)
				)
				(justify left bottom)
				(hide yes)
			)
		)
		(property "MPN" "GRM035R60J475ME15D"
			(at 166.37 181.61 0)
			(effects
				(font
					(size 1.27 1.27)
					(thickness 0.15)
				)
				(justify left bottom)
				(hide yes)
			)
		)
		(property "Val" "4u7"
			(at 183.515 201.295 90)
			(effects
				(font
					(size 1.27 1.27)
					(thickness 0.15)
				)
				(justify right)
			)
		)
		(property "License" "Apache-2.0"
			(at 161.29 181.61 0)
			(effects
				(font
					(size 1.27 1.27)
					(thickness 0.15)
				)
				(justify left bottom)
				(hide yes)
			)
		)
		(property "Author" "Antmicro"
			(at 158.75 181.61 0)
			(effects
				(font
					(size 1.27 1.27)
					(thickness 0.15)
				)
				(justify left bottom)
				(hide yes)
			)
		)
		(property "Voltage" ""
			(at 156.21 181.61 0)
			(effects
				(font
					(size 1.27 1.27)
				)
				(justify left bottom)
				(hide yes)
			)
		)
		(property "Dielectric" ""
			(at 153.67 181.61 0)
			(effects
				(font
					(size 1.27 1.27)
				)
				(justify left bottom)
				(hide yes)
			)
		)
		(pin "1"
		)
		(pin "2"
		)
		(instances
			(project "k410t-devboard"
				(path ""
					(reference "C28")
					(unit 1)
				)
			)
		)
	)
	(symbol
		(lib_id "antmicroCapacitorsmisc:C_4u7_0201")
		(at 172.72 36.83 90)
		(unit 1)
		(exclude_from_sim no)
		(in_bom yes)
		(on_board yes)
		(dnp no)
		(property "Reference" "C80"
			(at 173.355 32.385 90)
			(effects
				(font
					(size 1.27 1.27)
				)
				(justify right)
			)
		)
		(property "Value" "C_4u7_0201"
			(at 182.88 16.51 0)
			(effects
				(font
					(size 1.27 1.27)
					(thickness 0.15)
				)
				(justify left bottom)
				(hide yes)
			)
		)
		(property "Footprint" "antmicro-footprints:C_0201"
			(at 185.42 16.51 0)
			(effects
				(font
					(size 1.27 1.27)
					(thickness 0.15)
				)
				(justify left bottom)
				(hide yes)
			)
		)
		(property "Datasheet" "https://www.murata.com/products/productdetail?partno=GRM035R60J475ME15%23"
			(at 187.96 16.51 0)
			(effects
				(font
					(size 1.27 1.27)
					(thickness 0.15)
				)
				(justify left bottom)
				(hide yes)
			)
		)
		(property "Description" ""
			(at 172.72 36.83 0)
			(effects
				(font
					(size 1.27 1.27)
				)
			)
		)
		(property "Manufacturer" "Murata"
			(at 193.04 16.51 0)
			(effects
				(font
					(size 1.27 1.27)
					(thickness 0.15)
				)
				(justify left bottom)
				(hide yes)
			)
		)
		(property "MPN" "GRM035R60J475ME15D"
			(at 190.5 16.51 0)
			(effects
				(font
					(size 1.27 1.27)
					(thickness 0.15)
				)
				(justify left bottom)
				(hide yes)
			)
		)
		(property "Val" "4u7"
			(at 173.355 36.195 90)
			(effects
				(font
					(size 1.27 1.27)
					(thickness 0.15)
				)
				(justify right)
			)
		)
		(property "License" "Apache-2.0"
			(at 195.58 16.51 0)
			(effects
				(font
					(size 1.27 1.27)
					(thickness 0.15)
				)
				(justify left bottom)
				(hide yes)
			)
		)
		(property "Author" "Antmicro"
			(at 198.12 16.51 0)
			(effects
				(font
					(size 1.27 1.27)
					(thickness 0.15)
				)
				(justify left bottom)
				(hide yes)
			)
		)
		(property "Voltage" ""
			(at 200.66 16.51 0)
			(effects
				(font
					(size 1.27 1.27)
				)
				(justify left bottom)
				(hide yes)
			)
		)
		(property "Dielectric" ""
			(at 203.2 16.51 0)
			(effects
				(font
					(size 1.27 1.27)
				)
				(justify left bottom)
				(hide yes)
			)
		)
		(pin "1"
		)
		(pin "2"
		)
		(instances
			(project "k410t-devboard"
				(path ""
					(reference "C80")
					(unit 1)
				)
			)
		)
	)
	(symbol
		(lib_id "antmicroCapacitors0603:C_47u_0603")
		(at 138.43 238.76 270)
		(mirror x)
		(unit 1)
		(exclude_from_sim no)
		(in_bom yes)
		(on_board yes)
		(dnp no)
		(property "Reference" "C385"
			(at 137.795 234.315 90)
			(effects
				(font
					(size 1.27 1.27)
				)
				(justify right)
			)
		)
		(property "Value" "C_47u_0603"
			(at 128.27 218.44 0)
			(effects
				(font
					(size 1.27 1.27)
					(thickness 0.15)
				)
				(justify left bottom)
				(hide yes)
			)
		)
		(property "Footprint" "antmicro-footprints:C_0603_1608Metric"
			(at 125.73 218.44 0)
			(effects
				(font
					(size 1.27 1.27)
					(thickness 0.15)
				)
				(justify left bottom)
				(hide yes)
			)
		)
		(property "Datasheet" "https://www.murata.com/products/productdetail?partno=GRM188R60J476ME15%23"
			(at 123.19 218.44 0)
			(effects
				(font
					(size 1.27 1.27)
					(thickness 0.15)
				)
				(justify left bottom)
				(hide yes)
			)
		)
		(property "Description" ""
			(at 138.43 238.76 0)
			(effects
				(font
					(size 1.27 1.27)
				)
			)
		)
		(property "Manufacturer" "Murata"
			(at 118.11 218.44 0)
			(effects
				(font
					(size 1.27 1.27)
					(thickness 0.15)
				)
				(justify left bottom)
				(hide yes)
			)
		)
		(property "MPN" "GRM188R60J476ME15D"
			(at 120.65 218.44 0)
			(effects
				(font
					(size 1.27 1.27)
					(thickness 0.15)
				)
				(justify left bottom)
				(hide yes)
			)
		)
		(property "Val" "47u"
			(at 137.795 238.125 90)
			(effects
				(font
					(size 1.27 1.27)
					(thickness 0.15)
				)
				(justify right)
			)
		)
		(property "License" "Apache-2.0"
			(at 115.57 218.44 0)
			(effects
				(font
					(size 1.27 1.27)
					(thickness 0.15)
				)
				(justify left bottom)
				(hide yes)
			)
		)
		(property "Author" "Antmicro"
			(at 113.03 218.44 0)
			(effects
				(font
					(size 1.27 1.27)
					(thickness 0.15)
				)
				(justify left bottom)
				(hide yes)
			)
		)
		(property "Voltage" ""
			(at 110.49 218.44 0)
			(effects
				(font
					(size 1.27 1.27)
				)
				(justify left bottom)
				(hide yes)
			)
		)
		(property "Dielectric" ""
			(at 107.95 218.44 0)
			(effects
				(font
					(size 1.27 1.27)
				)
				(justify left bottom)
				(hide yes)
			)
		)
		(pin "1"
		)
		(pin "2"
		)
		(instances
			(project "k410t-devboard"
				(path ""
					(reference "C385")
					(unit 1)
				)
			)
		)
	)
	(symbol
		(lib_id "antmicropower:+1V8")
		(at 383.54 219.71 0)
		(mirror y)
		(unit 1)
		(exclude_from_sim no)
		(in_bom yes)
		(on_board yes)
		(dnp no)
		(property "Reference" "#PWR0427"
			(at 383.54 223.52 0)
			(effects
				(font
					(size 1.27 1.27)
				)
				(hide yes)
			)
		)
		(property "Value" "+1V8"
			(at 383.54 216.154 0)
			(effects
				(font
					(size 1.27 1.27)
				)
			)
		)
		(property "Footprint" ""
			(at 368.3 227.33 0)
			(effects
				(font
					(size 1.27 1.27)
					(thickness 0.15)
				)
				(justify left bottom)
				(hide yes)
			)
		)
		(property "Datasheet" ""
			(at 368.3 229.87 0)
			(effects
				(font
					(size 1.27 1.27)
					(thickness 0.15)
				)
				(justify left bottom)
				(hide yes)
			)
		)
		(property "Description" ""
			(at 383.54 219.71 0)
			(effects
				(font
					(size 1.27 1.27)
				)
			)
		)
		(property "Author" "Antmicro"
			(at 368.3 227.33 0)
			(effects
				(font
					(size 1.27 1.27)
					(thickness 0.15)
				)
				(justify left bottom)
				(hide yes)
			)
		)
		(property "License" "Apache-2.0"
			(at 368.3 229.87 0)
			(effects
				(font
					(size 1.27 1.27)
					(thickness 0.15)
				)
				(justify left bottom)
				(hide yes)
			)
		)
		(pin "1"
		)
		(instances
			(project "k410t-devboard"
				(path ""
					(reference "#PWR0427")
					(unit 1)
				)
			)
		)
	)
	(symbol
		(lib_id "antmicropower:GND")
		(at 229.87 186.69 0)
		(unit 1)
		(exclude_from_sim no)
		(in_bom yes)
		(on_board yes)
		(dnp no)
		(property "Reference" "#PWR022"
			(at 229.87 193.04 0)
			(effects
				(font
					(size 1.27 1.27)
				)
				(hide yes)
			)
		)
		(property "Value" "GND"
			(at 229.87 190.5 0)
			(effects
				(font
					(size 1.27 1.27)
				)
			)
		)
		(property "Footprint" ""
			(at 238.76 194.31 0)
			(effects
				(font
					(size 1.27 1.27)
					(thickness 0.15)
				)
				(justify left bottom)
				(hide yes)
			)
		)
		(property "Datasheet" ""
			(at 238.76 199.39 0)
			(effects
				(font
					(size 1.27 1.27)
					(thickness 0.15)
				)
				(justify left bottom)
				(hide yes)
			)
		)
		(property "Description" ""
			(at 229.87 186.69 0)
			(effects
				(font
					(size 1.27 1.27)
				)
			)
		)
		(property "Author" "Antmicro"
			(at 238.76 194.31 0)
			(effects
				(font
					(size 1.27 1.27)
					(thickness 0.15)
				)
				(justify left bottom)
				(hide yes)
			)
		)
		(property "License" "Apache-2.0"
			(at 238.76 196.85 0)
			(effects
				(font
					(size 1.27 1.27)
					(thickness 0.15)
				)
				(justify left bottom)
				(hide yes)
			)
		)
		(pin "1"
		)
		(instances
			(project "k410t-devboard"
				(path ""
					(reference "#PWR022")
					(unit 1)
				)
			)
		)
	)
	(symbol
		(lib_id "antmicroCapacitorsmisc:C_4u7_0201")
		(at 165.1 36.83 90)
		(unit 1)
		(exclude_from_sim no)
		(in_bom yes)
		(on_board yes)
		(dnp no)
		(property "Reference" "C66"
			(at 165.735 32.385 90)
			(effects
				(font
					(size 1.27 1.27)
				)
				(justify right)
			)
		)
		(property "Value" "C_4u7_0201"
			(at 175.26 16.51 0)
			(effects
				(font
					(size 1.27 1.27)
					(thickness 0.15)
				)
				(justify left bottom)
				(hide yes)
			)
		)
		(property "Footprint" "antmicro-footprints:C_0201"
			(at 177.8 16.51 0)
			(effects
				(font
					(size 1.27 1.27)
					(thickness 0.15)
				)
				(justify left bottom)
				(hide yes)
			)
		)
		(property "Datasheet" "https://www.murata.com/products/productdetail?partno=GRM035R60J475ME15%23"
			(at 180.34 16.51 0)
			(effects
				(font
					(size 1.27 1.27)
					(thickness 0.15)
				)
				(justify left bottom)
				(hide yes)
			)
		)
		(property "Description" ""
			(at 165.1 36.83 0)
			(effects
				(font
					(size 1.27 1.27)
				)
			)
		)
		(property "Manufacturer" "Murata"
			(at 185.42 16.51 0)
			(effects
				(font
					(size 1.27 1.27)
					(thickness 0.15)
				)
				(justify left bottom)
				(hide yes)
			)
		)
		(property "MPN" "GRM035R60J475ME15D"
			(at 182.88 16.51 0)
			(effects
				(font
					(size 1.27 1.27)
					(thickness 0.15)
				)
				(justify left bottom)
				(hide yes)
			)
		)
		(property "Val" "4u7"
			(at 165.735 36.195 90)
			(effects
				(font
					(size 1.27 1.27)
					(thickness 0.15)
				)
				(justify right)
			)
		)
		(property "License" "Apache-2.0"
			(at 187.96 16.51 0)
			(effects
				(font
					(size 1.27 1.27)
					(thickness 0.15)
				)
				(justify left bottom)
				(hide yes)
			)
		)
		(property "Author" "Antmicro"
			(at 190.5 16.51 0)
			(effects
				(font
					(size 1.27 1.27)
					(thickness 0.15)
				)
				(justify left bottom)
				(hide yes)
			)
		)
		(property "Voltage" ""
			(at 193.04 16.51 0)
			(effects
				(font
					(size 1.27 1.27)
				)
				(justify left bottom)
				(hide yes)
			)
		)
		(property "Dielectric" ""
			(at 195.58 16.51 0)
			(effects
				(font
					(size 1.27 1.27)
				)
				(justify left bottom)
				(hide yes)
			)
		)
		(pin "1"
		)
		(pin "2"
		)
		(instances
			(project "k410t-devboard"
				(path ""
					(reference "C66")
					(unit 1)
				)
			)
		)
	)
	(symbol
		(lib_id "antmicroGenericPinHeaders:PinHeader_2x3_P2.54mm_SMD")
		(at 379.73 222.25 0)
		(mirror y)
		(unit 1)
		(exclude_from_sim no)
		(in_bom yes)
		(on_board yes)
		(dnp no)
		(property "Reference" "J19"
			(at 374.65 219.71 0)
			(effects
				(font
					(size 1.27 1.27)
				)
			)
		)
		(property "Value" "PinHeader_2x3_P2.54mm_SMD"
			(at 354.33 229.87 0)
			(effects
				(font
					(size 1.27 1.27)
					(thickness 0.15)
				)
				(justify left bottom)
				(hide yes)
			)
		)
		(property "Footprint" "antmicro-footprints:PinHeader_2x3_P2.54mm_SMD"
			(at 354.33 232.41 0)
			(effects
				(font
					(size 1.27 1.27)
					(thickness 0.15)
				)
				(justify left bottom)
				(hide yes)
			)
		)
		(property "Datasheet" "https://www.molex.com/pdm_docs/sd/015910060_sd.pdf"
			(at 354.33 234.95 0)
			(effects
				(font
					(size 1.27 1.27)
					(thickness 0.15)
				)
				(justify left bottom)
				(hide yes)
			)
		)
		(property "Description" ""
			(at 379.73 222.25 0)
			(effects
				(font
					(size 1.27 1.27)
				)
			)
		)
		(property "MPN" "15910060"
			(at 354.33 237.49 0)
			(effects
				(font
					(size 1.27 1.27)
					(thickness 0.15)
				)
				(justify left bottom)
				(hide yes)
			)
		)
		(property "Manufacturer" "Molex"
			(at 354.33 240.03 0)
			(effects
				(font
					(size 1.27 1.27)
					(thickness 0.15)
				)
				(justify left bottom)
				(hide yes)
			)
		)
		(property "Author" "Antmicro"
			(at 354.33 242.57 0)
			(effects
				(font
					(size 1.27 1.27)
					(thickness 0.15)
				)
				(justify left bottom)
				(hide yes)
			)
		)
		(property "License" "Apache-2.0"
			(at 354.33 245.11 0)
			(effects
				(font
					(size 1.27 1.27)
					(thickness 0.15)
				)
				(justify left bottom)
				(hide yes)
			)
		)
		(pin "1"
		)
		(pin "2"
		)
		(pin "3"
		)
		(pin "4"
		)
		(pin "5"
		)
		(pin "6"
		)
		(instances
			(project "k410t-devboard"
				(path ""
					(reference "J19")
					(unit 1)
				)
			)
		)
	)
	(symbol
		(lib_id "antmicroCapacitors0402:C_100n_0402")
		(at 222.25 168.91 90)
		(unit 1)
		(exclude_from_sim no)
		(in_bom yes)
		(on_board yes)
		(dnp no)
		(property "Reference" "C59"
			(at 222.885 164.465 90)
			(effects
				(font
					(size 1.27 1.27)
				)
				(justify right)
			)
		)
		(property "Value" "C_100n_0402"
			(at 232.41 148.59 0)
			(effects
				(font
					(size 1.27 1.27)
					(thickness 0.15)
				)
				(justify left bottom)
				(hide yes)
			)
		)
		(property "Footprint" "antmicro-footprints:C_0402_1005Metric"
			(at 234.95 148.59 0)
			(effects
				(font
					(size 1.27 1.27)
					(thickness 0.15)
				)
				(justify left bottom)
				(hide yes)
			)
		)
		(property "Datasheet" "https://www.murata.com/products/productdetail?partno=GRM155R61H104KE14%23"
			(at 237.49 148.59 0)
			(effects
				(font
					(size 1.27 1.27)
					(thickness 0.15)
				)
				(justify left bottom)
				(hide yes)
			)
		)
		(property "Description" ""
			(at 222.25 168.91 0)
			(effects
				(font
					(size 1.27 1.27)
				)
			)
		)
		(property "Manufacturer" "Murata"
			(at 242.57 148.59 0)
			(effects
				(font
					(size 1.27 1.27)
					(thickness 0.15)
				)
				(justify left bottom)
				(hide yes)
			)
		)
		(property "MPN" "GRM155R61H104KE14D"
			(at 240.03 148.59 0)
			(effects
				(font
					(size 1.27 1.27)
					(thickness 0.15)
				)
				(justify left bottom)
				(hide yes)
			)
		)
		(property "Val" "100n"
			(at 222.885 168.275 90)
			(effects
				(font
					(size 1.27 1.27)
					(thickness 0.15)
				)
				(justify right)
			)
		)
		(property "License" "Apache-2.0"
			(at 245.11 148.59 0)
			(effects
				(font
					(size 1.27 1.27)
					(thickness 0.15)
				)
				(justify left bottom)
				(hide yes)
			)
		)
		(property "Author" "Antmicro"
			(at 247.65 148.59 0)
			(effects
				(font
					(size 1.27 1.27)
					(thickness 0.15)
				)
				(justify left bottom)
				(hide yes)
			)
		)
		(property "Voltage" "50V"
			(at 250.19 148.59 0)
			(effects
				(font
					(size 1.27 1.27)
				)
				(justify left bottom)
				(hide yes)
			)
		)
		(property "Dielectric" "X5R"
			(at 252.73 148.59 0)
			(effects
				(font
					(size 1.27 1.27)
				)
				(justify left bottom)
				(hide yes)
			)
		)
		(pin "1"
		)
		(pin "2"
		)
		(instances
			(project "k410t-devboard"
				(path ""
					(reference "C59")
					(unit 1)
				)
			)
		)
	)
	(symbol
		(lib_id "antmicroCapacitorsmisc:C_100n_0201")
		(at 203.2 93.98 90)
		(unit 1)
		(exclude_from_sim no)
		(in_bom yes)
		(on_board yes)
		(dnp no)
		(property "Reference" "C151"
			(at 203.835 89.535 90)
			(effects
				(font
					(size 1.27 1.27)
				)
				(justify right)
			)
		)
		(property "Value" "C_100n_0201"
			(at 213.36 73.66 0)
			(effects
				(font
					(size 1.27 1.27)
					(thickness 0.15)
				)
				(justify left bottom)
				(hide yes)
			)
		)
		(property "Footprint" "antmicro-footprints:C_0201"
			(at 215.9 73.66 0)
			(effects
				(font
					(size 1.27 1.27)
					(thickness 0.15)
				)
				(justify left bottom)
				(hide yes)
			)
		)
		(property "Datasheet" "https://www.yageo.com/en/Chart/Download/pdf/CC0201KRX6S5BB104"
			(at 218.44 73.66 0)
			(effects
				(font
					(size 1.27 1.27)
					(thickness 0.15)
				)
				(justify left bottom)
				(hide yes)
			)
		)
		(property "Description" ""
			(at 203.2 93.98 0)
			(effects
				(font
					(size 1.27 1.27)
				)
			)
		)
		(property "Manufacturer" "YAGEO"
			(at 223.52 73.66 0)
			(effects
				(font
					(size 1.27 1.27)
					(thickness 0.15)
				)
				(justify left bottom)
				(hide yes)
			)
		)
		(property "MPN" "CC0201KRX6S5BB104"
			(at 220.98 73.66 0)
			(effects
				(font
					(size 1.27 1.27)
					(thickness 0.15)
				)
				(justify left bottom)
				(hide yes)
			)
		)
		(property "Val" "100n"
			(at 203.835 93.345 90)
			(effects
				(font
					(size 1.27 1.27)
					(thickness 0.15)
				)
				(justify right)
			)
		)
		(property "License" "Apache-2.0"
			(at 226.06 73.66 0)
			(effects
				(font
					(size 1.27 1.27)
					(thickness 0.15)
				)
				(justify left bottom)
				(hide yes)
			)
		)
		(property "Author" "Antmicro"
			(at 228.6 73.66 0)
			(effects
				(font
					(size 1.27 1.27)
					(thickness 0.15)
				)
				(justify left bottom)
				(hide yes)
			)
		)
		(property "Voltage" ""
			(at 231.14 73.66 0)
			(effects
				(font
					(size 1.27 1.27)
				)
				(justify left bottom)
				(hide yes)
			)
		)
		(property "Dielectric" ""
			(at 233.68 73.66 0)
			(effects
				(font
					(size 1.27 1.27)
				)
				(justify left bottom)
				(hide yes)
			)
		)
		(pin "1"
		)
		(pin "2"
		)
		(instances
			(project "k410t-devboard"
				(path ""
					(reference "C151")
					(unit 1)
				)
			)
		)
	)
	(symbol
		(lib_id "antmicroCapacitors0402:C_100n_0402")
		(at 229.87 151.13 90)
		(unit 1)
		(exclude_from_sim no)
		(in_bom yes)
		(on_board yes)
		(dnp no)
		(property "Reference" "C63"
			(at 230.505 146.685 90)
			(effects
				(font
					(size 1.27 1.27)
				)
				(justify right)
			)
		)
		(property "Value" "C_100n_0402"
			(at 240.03 130.81 0)
			(effects
				(font
					(size 1.27 1.27)
					(thickness 0.15)
				)
				(justify left bottom)
				(hide yes)
			)
		)
		(property "Footprint" "antmicro-footprints:C_0402_1005Metric"
			(at 242.57 130.81 0)
			(effects
				(font
					(size 1.27 1.27)
					(thickness 0.15)
				)
				(justify left bottom)
				(hide yes)
			)
		)
		(property "Datasheet" "https://www.murata.com/products/productdetail?partno=GRM155R61H104KE14%23"
			(at 245.11 130.81 0)
			(effects
				(font
					(size 1.27 1.27)
					(thickness 0.15)
				)
				(justify left bottom)
				(hide yes)
			)
		)
		(property "Description" ""
			(at 229.87 151.13 0)
			(effects
				(font
					(size 1.27 1.27)
				)
			)
		)
		(property "Manufacturer" "Murata"
			(at 250.19 130.81 0)
			(effects
				(font
					(size 1.27 1.27)
					(thickness 0.15)
				)
				(justify left bottom)
				(hide yes)
			)
		)
		(property "MPN" "GRM155R61H104KE14D"
			(at 247.65 130.81 0)
			(effects
				(font
					(size 1.27 1.27)
					(thickness 0.15)
				)
				(justify left bottom)
				(hide yes)
			)
		)
		(property "Val" "100n"
			(at 230.505 150.495 90)
			(effects
				(font
					(size 1.27 1.27)
					(thickness 0.15)
				)
				(justify right)
			)
		)
		(property "License" "Apache-2.0"
			(at 252.73 130.81 0)
			(effects
				(font
					(size 1.27 1.27)
					(thickness 0.15)
				)
				(justify left bottom)
				(hide yes)
			)
		)
		(property "Author" "Antmicro"
			(at 255.27 130.81 0)
			(effects
				(font
					(size 1.27 1.27)
					(thickness 0.15)
				)
				(justify left bottom)
				(hide yes)
			)
		)
		(property "Voltage" "50V"
			(at 257.81 130.81 0)
			(effects
				(font
					(size 1.27 1.27)
				)
				(justify left bottom)
				(hide yes)
			)
		)
		(property "Dielectric" "X5R"
			(at 260.35 130.81 0)
			(effects
				(font
					(size 1.27 1.27)
				)
				(justify left bottom)
				(hide yes)
			)
		)
		(pin "1"
		)
		(pin "2"
		)
		(instances
			(project "k410t-devboard"
				(path ""
					(reference "C63")
					(unit 1)
				)
			)
		)
	)
	(symbol
		(lib_id "antmicroCapacitorsmisc:C_100n_0201")
		(at 229.87 185.42 90)
		(unit 1)
		(exclude_from_sim no)
		(in_bom yes)
		(on_board yes)
		(dnp no)
		(property "Reference" "C388"
			(at 230.505 180.975 90)
			(effects
				(font
					(size 1.27 1.27)
				)
				(justify right)
			)
		)
		(property "Value" "C_100n_0201"
			(at 240.03 165.1 0)
			(effects
				(font
					(size 1.27 1.27)
					(thickness 0.15)
				)
				(justify left bottom)
				(hide yes)
			)
		)
		(property "Footprint" "antmicro-footprints:C_0201"
			(at 242.57 165.1 0)
			(effects
				(font
					(size 1.27 1.27)
					(thickness 0.15)
				)
				(justify left bottom)
				(hide yes)
			)
		)
		(property "Datasheet" "https://www.yageo.com/en/Chart/Download/pdf/CC0201KRX6S5BB104"
			(at 245.11 165.1 0)
			(effects
				(font
					(size 1.27 1.27)
					(thickness 0.15)
				)
				(justify left bottom)
				(hide yes)
			)
		)
		(property "Description" ""
			(at 229.87 185.42 0)
			(effects
				(font
					(size 1.27 1.27)
				)
			)
		)
		(property "Manufacturer" "YAGEO"
			(at 250.19 165.1 0)
			(effects
				(font
					(size 1.27 1.27)
					(thickness 0.15)
				)
				(justify left bottom)
				(hide yes)
			)
		)
		(property "MPN" "CC0201KRX6S5BB104"
			(at 247.65 165.1 0)
			(effects
				(font
					(size 1.27 1.27)
					(thickness 0.15)
				)
				(justify left bottom)
				(hide yes)
			)
		)
		(property "Val" "100n"
			(at 230.505 184.785 90)
			(effects
				(font
					(size 1.27 1.27)
					(thickness 0.15)
				)
				(justify right)
			)
		)
		(property "License" "Apache-2.0"
			(at 252.73 165.1 0)
			(effects
				(font
					(size 1.27 1.27)
					(thickness 0.15)
				)
				(justify left bottom)
				(hide yes)
			)
		)
		(property "Author" "Antmicro"
			(at 255.27 165.1 0)
			(effects
				(font
					(size 1.27 1.27)
					(thickness 0.15)
				)
				(justify left bottom)
				(hide yes)
			)
		)
		(property "Voltage" ""
			(at 257.81 165.1 0)
			(effects
				(font
					(size 1.27 1.27)
				)
				(justify left bottom)
				(hide yes)
			)
		)
		(property "Dielectric" ""
			(at 260.35 165.1 0)
			(effects
				(font
					(size 1.27 1.27)
				)
				(justify left bottom)
				(hide yes)
			)
		)
		(pin "1"
		)
		(pin "2"
		)
		(instances
			(project "k410t-devboard"
				(path ""
					(reference "C388")
					(unit 1)
				)
			)
		)
	)
	(symbol
		(lib_name "XC7K410T-2FFG900I_4")
		(lib_id "antmicroFPGAChips:XC7K410T-2FFG900I")
		(at 250.19 173.99 0)
		(unit 10)
		(exclude_from_sim no)
		(in_bom yes)
		(on_board yes)
		(dnp no)
		(fields_autoplaced yes)
		(property "Reference" "U1"
			(at 267.335 167.005 0)
			(effects
				(font
					(size 1.27 1.27)
					(thickness 0.15)
				)
			)
		)
		(property "Value" "XC7K410T-2FFG900I"
			(at 267.335 169.545 0)
			(effects
				(font
					(size 1.27 1.27)
					(thickness 0.15)
				)
			)
		)
		(property "Footprint" "antmicro-footprints:BGA-900_31x31mm_Layout30x30_P1x1mm_FFG900"
			(at 250.19 147.32 0)
			(effects
				(font
					(size 1.27 1.27)
					(thickness 0.15)
				)
				(justify left bottom)
				(hide yes)
			)
		)
		(property "Datasheet" "https://eu.mouser.com/datasheet/2/903/ds180_7Series_Overview-1591537.pdf"
			(at 250.19 149.86 0)
			(effects
				(font
					(size 1.27 1.27)
					(thickness 0.15)
				)
				(justify left bottom)
				(hide yes)
			)
		)
		(property "Description" ""
			(at 250.19 173.99 0)
			(effects
				(font
					(size 1.27 1.27)
				)
			)
		)
		(property "Manufacturer" "AMD-Xilinx"
			(at 250.19 152.4 0)
			(effects
				(font
					(size 1.27 1.27)
					(thickness 0.15)
				)
				(justify left bottom)
				(hide yes)
			)
		)
		(property "MPN" "XC7K410T-2FFG900I"
			(at 250.19 154.94 0)
			(effects
				(font
					(size 1.27 1.27)
					(thickness 0.15)
				)
				(justify left bottom)
				(hide yes)
			)
		)
		(property "Author" "Antmicro"
			(at 250.19 157.48 0)
			(effects
				(font
					(size 1.27 1.27)
					(thickness 0.15)
				)
				(justify left bottom)
				(hide yes)
			)
		)
		(property "License" "Apache-2.0"
			(at 250.19 160.02 0)
			(effects
				(font
					(size 1.27 1.27)
					(thickness 0.15)
				)
				(justify left bottom)
				(hide yes)
			)
		)
		(pin "A1"
		)
		(pin "A14"
		)
		(pin "A2"
		)
		(pin "A24"
		)
		(pin "A5"
		)
		(pin "A6"
		)
		(pin "A9"
		)
		(pin "AA1"
		)
		(pin "AA14"
		)
		(pin "AA2"
		)
		(pin "AA24"
		)
		(pin "AA5"
		)
		(pin "AA6"
		)
		(pin "AA7"
		)
		(pin "AB11"
		)
		(pin "AB21"
		)
		(pin "AB3"
		)
		(pin "AB4"
		)
		(pin "AC18"
		)
		(pin "AC28"
		)
		(pin "AC8"
		)
		(pin "AD15"
		)
		(pin "AD25"
		)
		(pin "AD5"
		)
		(pin "AE12"
		)
		(pin "AE2"
		)
		(pin "AE22"
		)
		(pin "AF19"
		)
		(pin "AF29"
		)
		(pin "AF9"
		)
		(pin "AG16"
		)
		(pin "AG26"
		)
		(pin "AG6"
		)
		(pin "AH13"
		)
		(pin "AH23"
		)
		(pin "AH3"
		)
		(pin "AJ10"
		)
		(pin "AJ20"
		)
		(pin "AJ30"
		)
		(pin "AK17"
		)
		(pin "AK27"
		)
		(pin "AK7"
		)
		(pin "B11"
		)
		(pin "B21"
		)
		(pin "B4"
		)
		(pin "B8"
		)
		(pin "B9"
		)
		(pin "C1"
		)
		(pin "C10"
		)
		(pin "C18"
		)
		(pin "C2"
		)
		(pin "C28"
		)
		(pin "C6"
		)
		(pin "C9"
		)
		(pin "D15"
		)
		(pin "D25"
		)
		(pin "D4"
		)
		(pin "D8"
		)
		(pin "D9"
		)
		(pin "E1"
		)
		(pin "E12"
		)
		(pin "E2"
		)
		(pin "E22"
		)
		(pin "E6"
		)
		(pin "E9"
		)
		(pin "F19"
		)
		(pin "F29"
		)
		(pin "F4"
		)
		(pin "F8"
		)
		(pin "F9"
		)
		(pin "G1"
		)
		(pin "G16"
		)
		(pin "G2"
		)
		(pin "G26"
		)
		(pin "G6"
		)
		(pin "G9"
		)
		(pin "H13"
		)
		(pin "H23"
		)
		(pin "H4"
		)
		(pin "H8"
		)
		(pin "H9"
		)
		(pin "J1"
		)
		(pin "J10"
		)
		(pin "J2"
		)
		(pin "J20"
		)
		(pin "J30"
		)
		(pin "J6"
		)
		(pin "J9"
		)
		(pin "K17"
		)
		(pin "K27"
		)
		(pin "K4"
		)
		(pin "K8"
		)
		(pin "K9"
		)
		(pin "L1"
		)
		(pin "L14"
		)
		(pin "L2"
		)
		(pin "L24"
		)
		(pin "L6"
		)
		(pin "L9"
		)
		(pin "M11"
		)
		(pin "M12"
		)
		(pin "M13"
		)
		(pin "M14"
		)
		(pin "M15"
		)
		(pin "M16"
		)
		(pin "M17"
		)
		(pin "M18"
		)
		(pin "M21"
		)
		(pin "M4"
		)
		(pin "M8"
		)
		(pin "M9"
		)
		(pin "N1"
		)
		(pin "N10"
		)
		(pin "N11"
		)
		(pin "N12"
		)
		(pin "N13"
		)
		(pin "N14"
		)
		(pin "N15"
		)
		(pin "N16"
		)
		(pin "N17"
		)
		(pin "N18"
		)
		(pin "N2"
		)
		(pin "N28"
		)
		(pin "N6"
		)
		(pin "N9"
		)
		(pin "P10"
		)
		(pin "P11"
		)
		(pin "P12"
		)
		(pin "P13"
		)
		(pin "P14"
		)
		(pin "P15"
		)
		(pin "P16"
		)
		(pin "P17"
		)
		(pin "P18"
		)
		(pin "P25"
		)
		(pin "P4"
		)
		(pin "P8"
		)
		(pin "P9"
		)
		(pin "R1"
		)
		(pin "R10"
		)
		(pin "R11"
		)
		(pin "R12"
		)
		(pin "R13"
		)
		(pin "R16"
		)
		(pin "R17"
		)
		(pin "R18"
		)
		(pin "R2"
		)
		(pin "R22"
		)
		(pin "R6"
		)
		(pin "R9"
		)
		(pin "T10"
		)
		(pin "T11"
		)
		(pin "T12"
		)
		(pin "T13"
		)
		(pin "T16"
		)
		(pin "T17"
		)
		(pin "T18"
		)
		(pin "T19"
		)
		(pin "T29"
		)
		(pin "T4"
		)
		(pin "T8"
		)
		(pin "U1"
		)
		(pin "U10"
		)
		(pin "U11"
		)
		(pin "U12"
		)
		(pin "U13"
		)
		(pin "U16"
		)
		(pin "U17"
		)
		(pin "U18"
		)
		(pin "U2"
		)
		(pin "U26"
		)
		(pin "U6"
		)
		(pin "U9"
		)
		(pin "V10"
		)
		(pin "V11"
		)
		(pin "V12"
		)
		(pin "V13"
		)
		(pin "V14"
		)
		(pin "V15"
		)
		(pin "V16"
		)
		(pin "V17"
		)
		(pin "V18"
		)
		(pin "V23"
		)
		(pin "V4"
		)
		(pin "V8"
		)
		(pin "V9"
		)
		(pin "W1"
		)
		(pin "W10"
		)
		(pin "W11"
		)
		(pin "W12"
		)
		(pin "W13"
		)
		(pin "W14"
		)
		(pin "W15"
		)
		(pin "W16"
		)
		(pin "W17"
		)
		(pin "W18"
		)
		(pin "W2"
		)
		(pin "W20"
		)
		(pin "W30"
		)
		(pin "W6"
		)
		(pin "W9"
		)
		(pin "Y17"
		)
		(pin "Y27"
		)
		(pin "Y3"
		)
		(pin "Y4"
		)
		(pin "Y7"
		)
		(pin "Y8"
		)
		(pin "Y9"
		)
		(pin "AA20"
		)
		(pin "AA21"
		)
		(pin "AA22"
		)
		(pin "AA23"
		)
		(pin "AB20"
		)
		(pin "AB22"
		)
		(pin "AB23"
		)
		(pin "AB24"
		)
		(pin "AC20"
		)
		(pin "AC21"
		)
		(pin "AC22"
		)
		(pin "AC24"
		)
		(pin "AC25"
		)
		(pin "AD21"
		)
		(pin "AD22"
		)
		(pin "AD23"
		)
		(pin "AD24"
		)
		(pin "AE20"
		)
		(pin "AE21"
		)
		(pin "AE23"
		)
		(pin "AE24"
		)
		(pin "AE25"
		)
		(pin "AF20"
		)
		(pin "AF21"
		)
		(pin "AF22"
		)
		(pin "AF23"
		)
		(pin "AF25"
		)
		(pin "AG20"
		)
		(pin "AG22"
		)
		(pin "AG23"
		)
		(pin "AG24"
		)
		(pin "AG25"
		)
		(pin "AH20"
		)
		(pin "AH21"
		)
		(pin "AH22"
		)
		(pin "AH24"
		)
		(pin "AH25"
		)
		(pin "AJ21"
		)
		(pin "AJ22"
		)
		(pin "AJ23"
		)
		(pin "AJ24"
		)
		(pin "AK20"
		)
		(pin "AK21"
		)
		(pin "AK23"
		)
		(pin "AK24"
		)
		(pin "AK25"
		)
		(pin "Y20"
		)
		(pin "Y21"
		)
		(pin "Y23"
		)
		(pin "Y24"
		)
		(pin "P24"
		)
		(pin "P26"
		)
		(pin "P27"
		)
		(pin "P28"
		)
		(pin "P29"
		)
		(pin "R19"
		)
		(pin "R20"
		)
		(pin "R21"
		)
		(pin "R23"
		)
		(pin "R24"
		)
		(pin "R25"
		)
		(pin "R26"
		)
		(pin "R28"
		)
		(pin "R29"
		)
		(pin "R30"
		)
		(pin "T20"
		)
		(pin "T21"
		)
		(pin "T22"
		)
		(pin "T23"
		)
		(pin "T25"
		)
		(pin "T26"
		)
		(pin "T27"
		)
		(pin "T28"
		)
		(pin "T30"
		)
		(pin "U19"
		)
		(pin "U20"
		)
		(pin "U22"
		)
		(pin "U23"
		)
		(pin "U24"
		)
		(pin "U25"
		)
		(pin "U27"
		)
		(pin "U28"
		)
		(pin "U29"
		)
		(pin "U30"
		)
		(pin "V19"
		)
		(pin "V20"
		)
		(pin "V21"
		)
		(pin "V22"
		)
		(pin "V24"
		)
		(pin "V25"
		)
		(pin "V26"
		)
		(pin "V27"
		)
		(pin "V29"
		)
		(pin "V30"
		)
		(pin "W19"
		)
		(pin "W21"
		)
		(pin "W22"
		)
		(pin "W23"
		)
		(pin "W24"
		)
		(pin "W26"
		)
		(pin "A23"
		)
		(pin "A25"
		)
		(pin "A26"
		)
		(pin "A27"
		)
		(pin "A28"
		)
		(pin "A30"
		)
		(pin "B23"
		)
		(pin "B24"
		)
		(pin "B25"
		)
		(pin "B27"
		)
		(pin "B28"
		)
		(pin "B29"
		)
		(pin "B30"
		)
		(pin "C24"
		)
		(pin "C25"
		)
		(pin "C26"
		)
		(pin "C27"
		)
		(pin "C29"
		)
		(pin "C30"
		)
		(pin "D23"
		)
		(pin "D24"
		)
		(pin "D26"
		)
		(pin "D27"
		)
		(pin "D28"
		)
		(pin "D29"
		)
		(pin "E23"
		)
		(pin "E24"
		)
		(pin "E25"
		)
		(pin "E26"
		)
		(pin "B2"
		)
		(pin "B5"
		)
		(pin "B6"
		)
		(pin "C3"
		)
		(pin "C4"
		)
		(pin "E28"
		)
		(pin "E29"
		)
		(pin "E30"
		)
		(pin "F23"
		)
		(pin "F25"
		)
		(pin "F26"
		)
		(pin "F27"
		)
		(pin "F28"
		)
		(pin "F30"
		)
		(pin "G23"
		)
		(pin "G24"
		)
		(pin "G25"
		)
		(pin "G27"
		)
		(pin "G28"
		)
		(pin "G29"
		)
		(pin "G30"
		)
		(pin "H24"
		)
		(pin "H25"
		)
		(pin "H26"
		)
		(pin "H27"
		)
		(pin "H30"
		)
		(pin "A11"
		)
		(pin "A12"
		)
		(pin "A13"
		)
		(pin "A15"
		)
		(pin "B12"
		)
		(pin "B13"
		)
		(pin "B14"
		)
		(pin "B15"
		)
		(pin "C11"
		)
		(pin "C12"
		)
		(pin "C14"
		)
		(pin "C15"
		)
		(pin "D11"
		)
		(pin "D12"
		)
		(pin "D13"
		)
		(pin "D14"
		)
		(pin "E11"
		)
		(pin "E13"
		)
		(pin "E14"
		)
		(pin "E15"
		)
		(pin "E16"
		)
		(pin "F11"
		)
		(pin "F12"
		)
		(pin "F13"
		)
		(pin "F15"
		)
		(pin "F16"
		)
		(pin "G12"
		)
		(pin "G13"
		)
		(pin "G14"
		)
		(pin "G15"
		)
		(pin "H11"
		)
		(pin "H12"
		)
		(pin "H14"
		)
		(pin "H15"
		)
		(pin "H16"
		)
		(pin "J11"
		)
		(pin "J12"
		)
		(pin "J13"
		)
		(pin "J14"
		)
		(pin "J16"
		)
		(pin "K11"
		)
		(pin "K13"
		)
		(pin "K14"
		)
		(pin "K15"
		)
		(pin "K16"
		)
		(pin "L11"
		)
		(pin "L12"
		)
		(pin "L13"
		)
		(pin "L15"
		)
		(pin "L16"
		)
		(pin "AA10"
		)
		(pin "AA11"
		)
		(pin "AA12"
		)
		(pin "AA13"
		)
		(pin "AA8"
		)
		(pin "AB10"
		)
		(pin "AB12"
		)
		(pin "AB13"
		)
		(pin "AB8"
		)
		(pin "AB9"
		)
		(pin "AC10"
		)
		(pin "AC11"
		)
		(pin "AC12"
		)
		(pin "AC9"
		)
		(pin "AD11"
		)
		(pin "AD12"
		)
		(pin "AD13"
		)
		(pin "AD8"
		)
		(pin "AD9"
		)
		(pin "AE10"
		)
		(pin "AE11"
		)
		(pin "AE13"
		)
		(pin "AE8"
		)
		(pin "AE9"
		)
		(pin "AF10"
		)
		(pin "AF11"
		)
		(pin "AF12"
		)
		(pin "AF13"
		)
		(pin "AG10"
		)
		(pin "AG12"
		)
		(pin "AG13"
		)
		(pin "AG9"
		)
		(pin "AH10"
		)
		(pin "AH11"
		)
		(pin "AH12"
		)
		(pin "AH14"
		)
		(pin "AH9"
		)
		(pin "AJ11"
		)
		(pin "AJ12"
		)
		(pin "AJ13"
		)
		(pin "AJ14"
		)
		(pin "AJ9"
		)
		(pin "AK10"
		)
		(pin "AK11"
		)
		(pin "AK13"
		)
		(pin "AK14"
		)
		(pin "AK9"
		)
		(pin "Y10"
		)
		(pin "Y11"
		)
		(pin "Y13"
		)
		(pin "A3"
		)
		(pin "A4"
		)
		(pin "A7"
		)
		(pin "A8"
		)
		(pin "AA3"
		)
		(pin "AA4"
		)
		(pin "B1"
		)
		(pin "C7"
		)
		(pin "C8"
		)
		(pin "D1"
		)
		(pin "D2"
		)
		(pin "D5"
		)
		(pin "D6"
		)
		(pin "E3"
		)
		(pin "E4"
		)
		(pin "E7"
		)
		(pin "E8"
		)
		(pin "F1"
		)
		(pin "F2"
		)
		(pin "F5"
		)
		(pin "F6"
		)
		(pin "G3"
		)
		(pin "G4"
		)
		(pin "G7"
		)
		(pin "G8"
		)
		(pin "H1"
		)
		(pin "H2"
		)
		(pin "H5"
		)
		(pin "H6"
		)
		(pin "J3"
		)
		(pin "J4"
		)
		(pin "J7"
		)
		(pin "J8"
		)
		(pin "K1"
		)
		(pin "K2"
		)
		(pin "K5"
		)
		(pin "K6"
		)
		(pin "L3"
		)
		(pin "L4"
		)
		(pin "L7"
		)
		(pin "L8"
		)
		(pin "M1"
		)
		(pin "M2"
		)
		(pin "M5"
		)
		(pin "M6"
		)
		(pin "N3"
		)
		(pin "N4"
		)
		(pin "N7"
		)
		(pin "N8"
		)
		(pin "P1"
		)
		(pin "P2"
		)
		(pin "P5"
		)
		(pin "P6"
		)
		(pin "R3"
		)
		(pin "R4"
		)
		(pin "R7"
		)
		(pin "R8"
		)
		(pin "T1"
		)
		(pin "T2"
		)
		(pin "T5"
		)
		(pin "T6"
		)
		(pin "U3"
		)
		(pin "U4"
		)
		(pin "U7"
		)
		(pin "U8"
		)
		(pin "V1"
		)
		(pin "V2"
		)
		(pin "V5"
		)
		(pin "V6"
		)
		(pin "W3"
		)
		(pin "W4"
		)
		(pin "Y1"
		)
		(pin "Y2"
		)
		(pin "Y5"
		)
		(pin "Y6"
		)
		(pin "B3"
		)
		(pin "B7"
		)
		(pin "C5"
		)
		(pin "D3"
		)
		(pin "D7"
		)
		(pin "E5"
		)
		(pin "F3"
		)
		(pin "F7"
		)
		(pin "G5"
		)
		(pin "H3"
		)
		(pin "H7"
		)
		(pin "J5"
		)
		(pin "K3"
		)
		(pin "K7"
		)
		(pin "L5"
		)
		(pin "M3"
		)
		(pin "M7"
		)
		(pin "N5"
		)
		(pin "P3"
		)
		(pin "P7"
		)
		(pin "R5"
		)
		(pin "T3"
		)
		(pin "T7"
		)
		(pin "U5"
		)
		(pin "V3"
		)
		(pin "V7"
		)
		(pin "W5"
		)
		(pin "W7"
		)
		(pin "W8"
		)
		(pin "A10"
		)
		(pin "AB1"
		)
		(pin "AB2"
		)
		(pin "AB5"
		)
		(pin "B10"
		)
		(pin "E10"
		)
		(pin "F10"
		)
		(pin "G10"
		)
		(pin "H10"
		)
		(pin "K10"
		)
		(pin "L10"
		)
		(pin "M10"
		)
		(pin "R14"
		)
		(pin "R15"
		)
		(pin "T14"
		)
		(pin "T15"
		)
		(pin "U14"
		)
		(pin "U15"
		)
		(pin "A19"
		)
		(pin "A29"
		)
		(pin "AA19"
		)
		(pin "AA29"
		)
		(pin "AA9"
		)
		(pin "AB16"
		)
		(pin "AB26"
		)
		(pin "AB6"
		)
		(pin "AC13"
		)
		(pin "AC23"
		)
		(pin "AC3"
		)
		(pin "AD10"
		)
		(pin "AD20"
		)
		(pin "AD30"
		)
		(pin "AE17"
		)
		(pin "AE27"
		)
		(pin "AE7"
		)
		(pin "AF14"
		)
		(pin "AF24"
		)
		(pin "AF4"
		)
		(pin "AG1"
		)
		(pin "AG11"
		)
		(pin "AG21"
		)
		(pin "AH18"
		)
		(pin "AH28"
		)
		(pin "AH8"
		)
		(pin "AJ15"
		)
		(pin "AJ25"
		)
		(pin "AJ5"
		)
		(pin "AK12"
		)
		(pin "AK2"
		)
		(pin "AK22"
		)
		(pin "B16"
		)
		(pin "B26"
		)
		(pin "C13"
		)
		(pin "C23"
		)
		(pin "D10"
		)
		(pin "D20"
		)
		(pin "D30"
		)
		(pin "E17"
		)
		(pin "E27"
		)
		(pin "F14"
		)
		(pin "F24"
		)
		(pin "G11"
		)
		(pin "G21"
		)
		(pin "H18"
		)
		(pin "H28"
		)
		(pin "J15"
		)
		(pin "J25"
		)
		(pin "K12"
		)
		(pin "K22"
		)
		(pin "L19"
		)
		(pin "L29"
		)
		(pin "M26"
		)
		(pin "N23"
		)
		(pin "P20"
		)
		(pin "P30"
		)
		(pin "R27"
		)
		(pin "T24"
		)
		(pin "T9"
		)
		(pin "U21"
		)
		(pin "V28"
		)
		(pin "W25"
		)
		(pin "Y12"
		)
		(pin "Y22"
		)
		(pin "AA25"
		)
		(pin "AA26"
		)
		(pin "AA27"
		)
		(pin "AA28"
		)
		(pin "AA30"
		)
		(pin "AB25"
		)
		(pin "AB27"
		)
		(pin "AB28"
		)
		(pin "AB29"
		)
		(pin "AB30"
		)
		(pin "AC26"
		)
		(pin "AC27"
		)
		(pin "AC29"
		)
		(pin "AC30"
		)
		(pin "AD26"
		)
		(pin "AD27"
		)
		(pin "AD28"
		)
		(pin "AD29"
		)
		(pin "AE26"
		)
		(pin "AE28"
		)
		(pin "AE29"
		)
		(pin "AE30"
		)
		(pin "AF26"
		)
		(pin "AF27"
		)
		(pin "AF28"
		)
		(pin "AF30"
		)
		(pin "AG27"
		)
		(pin "AG28"
		)
		(pin "AG29"
		)
		(pin "AG30"
		)
		(pin "AH26"
		)
		(pin "AH27"
		)
		(pin "AH29"
		)
		(pin "AH30"
		)
		(pin "AJ26"
		)
		(pin "AJ27"
		)
		(pin "AJ28"
		)
		(pin "AJ29"
		)
		(pin "AK26"
		)
		(pin "AK28"
		)
		(pin "AK29"
		)
		(pin "AK30"
		)
		(pin "W27"
		)
		(pin "W28"
		)
		(pin "W29"
		)
		(pin "Y25"
		)
		(pin "Y26"
		)
		(pin "Y28"
		)
		(pin "Y29"
		)
		(pin "Y30"
		)
		(pin "H29"
		)
		(pin "J21"
		)
		(pin "J22"
		)
		(pin "J23"
		)
		(pin "J24"
		)
		(pin "J26"
		)
		(pin "J27"
		)
		(pin "J28"
		)
		(pin "J29"
		)
		(pin "K21"
		)
		(pin "K23"
		)
		(pin "K24"
		)
		(pin "K25"
		)
		(pin "K26"
		)
		(pin "K28"
		)
		(pin "K29"
		)
		(pin "K30"
		)
		(pin "L20"
		)
		(pin "L21"
		)
		(pin "L22"
		)
		(pin "L23"
		)
		(pin "L25"
		)
		(pin "L26"
		)
		(pin "L27"
		)
		(pin "L28"
		)
		(pin "L30"
		)
		(pin "M19"
		)
		(pin "M20"
		)
		(pin "M22"
		)
		(pin "M23"
		)
		(pin "M24"
		)
		(pin "M25"
		)
		(pin "M27"
		)
		(pin "M28"
		)
		(pin "M29"
		)
		(pin "M30"
		)
		(pin "N19"
		)
		(pin "N20"
		)
		(pin "N21"
		)
		(pin "N22"
		)
		(pin "N24"
		)
		(pin "N25"
		)
		(pin "N26"
		)
		(pin "N27"
		)
		(pin "N29"
		)
		(pin "N30"
		)
		(pin "P19"
		)
		(pin "P21"
		)
		(pin "P22"
		)
		(pin "P23"
		)
		(pin "A16"
		)
		(pin "A17"
		)
		(pin "A18"
		)
		(pin "A20"
		)
		(pin "A21"
		)
		(pin "A22"
		)
		(pin "B17"
		)
		(pin "B18"
		)
		(pin "B19"
		)
		(pin "B20"
		)
		(pin "B22"
		)
		(pin "C16"
		)
		(pin "C17"
		)
		(pin "C19"
		)
		(pin "C20"
		)
		(pin "C21"
		)
		(pin "C22"
		)
		(pin "D16"
		)
		(pin "D17"
		)
		(pin "D18"
		)
		(pin "D19"
		)
		(pin "D21"
		)
		(pin "D22"
		)
		(pin "E18"
		)
		(pin "E19"
		)
		(pin "E20"
		)
		(pin "E21"
		)
		(pin "F17"
		)
		(pin "F18"
		)
		(pin "F20"
		)
		(pin "F21"
		)
		(pin "F22"
		)
		(pin "G17"
		)
		(pin "G18"
		)
		(pin "G19"
		)
		(pin "G20"
		)
		(pin "G22"
		)
		(pin "H17"
		)
		(pin "H19"
		)
		(pin "H20"
		)
		(pin "H21"
		)
		(pin "H22"
		)
		(pin "J17"
		)
		(pin "J18"
		)
		(pin "J19"
		)
		(pin "K18"
		)
		(pin "K19"
		)
		(pin "K20"
		)
		(pin "L17"
		)
		(pin "L18"
		)
		(pin "AA15"
		)
		(pin "AA16"
		)
		(pin "AA17"
		)
		(pin "AA18"
		)
		(pin "AB14"
		)
		(pin "AB15"
		)
		(pin "AB17"
		)
		(pin "AB18"
		)
		(pin "AB19"
		)
		(pin "AC14"
		)
		(pin "AC15"
		)
		(pin "AC16"
		)
		(pin "AC17"
		)
		(pin "AC19"
		)
		(pin "AD14"
		)
		(pin "AD16"
		)
		(pin "AD17"
		)
		(pin "AD18"
		)
		(pin "AD19"
		)
		(pin "AE14"
		)
		(pin "AE15"
		)
		(pin "AE16"
		)
		(pin "AE18"
		)
		(pin "AE19"
		)
		(pin "AF15"
		)
		(pin "AF16"
		)
		(pin "AF17"
		)
		(pin "AF18"
		)
		(pin "AG14"
		)
		(pin "AG15"
		)
		(pin "AG17"
		)
		(pin "AG18"
		)
		(pin "AG19"
		)
		(pin "AH15"
		)
		(pin "AH16"
		)
		(pin "AH17"
		)
		(pin "AH19"
		)
		(pin "AJ16"
		)
		(pin "AJ17"
		)
		(pin "AJ18"
		)
		(pin "AJ19"
		)
		(pin "AK15"
		)
		(pin "AK16"
		)
		(pin "AK18"
		)
		(pin "AK19"
		)
		(pin "Y14"
		)
		(pin "Y15"
		)
		(pin "Y16"
		)
		(pin "Y18"
		)
		(pin "Y19"
		)
		(pin "AB7"
		)
		(pin "AC1"
		)
		(pin "AC2"
		)
		(pin "AC4"
		)
		(pin "AC5"
		)
		(pin "AC6"
		)
		(pin "AC7"
		)
		(pin "AD1"
		)
		(pin "AD2"
		)
		(pin "AD3"
		)
		(pin "AD4"
		)
		(pin "AD6"
		)
		(pin "AD7"
		)
		(pin "AE1"
		)
		(pin "AE3"
		)
		(pin "AE4"
		)
		(pin "AE5"
		)
		(pin "AE6"
		)
		(pin "AF1"
		)
		(pin "AF2"
		)
		(pin "AF3"
		)
		(pin "AF5"
		)
		(pin "AF6"
		)
		(pin "AF7"
		)
		(pin "AF8"
		)
		(pin "AG2"
		)
		(pin "AG3"
		)
		(pin "AG4"
		)
		(pin "AG5"
		)
		(pin "AG7"
		)
		(pin "AG8"
		)
		(pin "AH1"
		)
		(pin "AH2"
		)
		(pin "AH4"
		)
		(pin "AH5"
		)
		(pin "AH6"
		)
		(pin "AH7"
		)
		(pin "AJ1"
		)
		(pin "AJ2"
		)
		(pin "AJ3"
		)
		(pin "AJ4"
		)
		(pin "AJ6"
		)
		(pin "AJ7"
		)
		(pin "AJ8"
		)
		(pin "AK1"
		)
		(pin "AK3"
		)
		(pin "AK4"
		)
		(pin "AK5"
		)
		(pin "AK6"
		)
		(pin "AK8"
		)
		(instances
			(project "k410t-devboard"
				(path ""
					(reference "U1")
					(unit 10)
				)
			)
		)
	)
	(symbol
		(lib_id "antmicropower:+1V8")
		(at 214.63 160.02 0)
		(unit 1)
		(exclude_from_sim no)
		(in_bom yes)
		(on_board yes)
		(dnp no)
		(property "Reference" "#PWR015"
			(at 214.63 163.83 0)
			(effects
				(font
					(size 1.27 1.27)
				)
				(hide yes)
			)
		)
		(property "Value" "+1V8"
			(at 214.63 156.464 0)
			(effects
				(font
					(size 1.27 1.27)
				)
			)
		)
		(property "Footprint" ""
			(at 229.87 167.64 0)
			(effects
				(font
					(size 1.27 1.27)
					(thickness 0.15)
				)
				(justify left bottom)
				(hide yes)
			)
		)
		(property "Datasheet" ""
			(at 229.87 170.18 0)
			(effects
				(font
					(size 1.27 1.27)
					(thickness 0.15)
				)
				(justify left bottom)
				(hide yes)
			)
		)
		(property "Description" ""
			(at 214.63 160.02 0)
			(effects
				(font
					(size 1.27 1.27)
				)
			)
		)
		(property "Author" "Antmicro"
			(at 229.87 167.64 0)
			(effects
				(font
					(size 1.27 1.27)
					(thickness 0.15)
				)
				(justify left bottom)
				(hide yes)
			)
		)
		(property "License" "Apache-2.0"
			(at 229.87 170.18 0)
			(effects
				(font
					(size 1.27 1.27)
					(thickness 0.15)
				)
				(justify left bottom)
				(hide yes)
			)
		)
		(pin "1"
		)
		(instances
			(project "k410t-devboard"
				(path ""
					(reference "#PWR015")
					(unit 1)
				)
			)
		)
	)
	(symbol
		(lib_id "antmicropower:+1V2")
		(at 360.68 224.79 0)
		(mirror y)
		(unit 1)
		(exclude_from_sim no)
		(in_bom yes)
		(on_board yes)
		(dnp no)
		(property "Reference" "#PWR0356"
			(at 360.68 228.6 0)
			(effects
				(font
					(size 1.27 1.27)
				)
				(hide yes)
			)
		)
		(property "Value" "+1V2"
			(at 360.68 221.234 0)
			(effects
				(font
					(size 1.27 1.27)
				)
			)
		)
		(property "Footprint" ""
			(at 360.68 224.79 0)
			(effects
				(font
					(size 1.27 1.27)
				)
				(hide yes)
			)
		)
		(property "Datasheet" ""
			(at 360.68 224.79 0)
			(effects
				(font
					(size 1.27 1.27)
				)
				(hide yes)
			)
		)
		(property "Description" ""
			(at 360.68 224.79 0)
			(effects
				(font
					(size 1.27 1.27)
				)
			)
		)
		(pin "1"
		)
		(instances
			(project "k410t-devboard"
				(path ""
					(reference "#PWR0356")
					(unit 1)
				)
			)
		)
	)
	(symbol
		(lib_id "antmicroCapacitorsmisc:C_100n_0201")
		(at 191.77 220.98 270)
		(mirror x)
		(unit 1)
		(exclude_from_sim no)
		(in_bom yes)
		(on_board yes)
		(dnp no)
		(property "Reference" "C135"
			(at 191.135 216.535 90)
			(effects
				(font
					(size 1.27 1.27)
				)
				(justify right)
			)
		)
		(property "Value" "C_100n_0201"
			(at 181.61 200.66 0)
			(effects
				(font
					(size 1.27 1.27)
					(thickness 0.15)
				)
				(justify left bottom)
				(hide yes)
			)
		)
		(property "Footprint" "antmicro-footprints:C_0201"
			(at 179.07 200.66 0)
			(effects
				(font
					(size 1.27 1.27)
					(thickness 0.15)
				)
				(justify left bottom)
				(hide yes)
			)
		)
		(property "Datasheet" "https://www.yageo.com/en/Chart/Download/pdf/CC0201KRX6S5BB104"
			(at 176.53 200.66 0)
			(effects
				(font
					(size 1.27 1.27)
					(thickness 0.15)
				)
				(justify left bottom)
				(hide yes)
			)
		)
		(property "Description" ""
			(at 191.77 220.98 0)
			(effects
				(font
					(size 1.27 1.27)
				)
			)
		)
		(property "Manufacturer" "YAGEO"
			(at 171.45 200.66 0)
			(effects
				(font
					(size 1.27 1.27)
					(thickness 0.15)
				)
				(justify left bottom)
				(hide yes)
			)
		)
		(property "MPN" "CC0201KRX6S5BB104"
			(at 173.99 200.66 0)
			(effects
				(font
					(size 1.27 1.27)
					(thickness 0.15)
				)
				(justify left bottom)
				(hide yes)
			)
		)
		(property "Val" "100n"
			(at 191.135 220.345 90)
			(effects
				(font
					(size 1.27 1.27)
					(thickness 0.15)
				)
				(justify right)
			)
		)
		(property "License" "Apache-2.0"
			(at 168.91 200.66 0)
			(effects
				(font
					(size 1.27 1.27)
					(thickness 0.15)
				)
				(justify left bottom)
				(hide yes)
			)
		)
		(property "Author" "Antmicro"
			(at 166.37 200.66 0)
			(effects
				(font
					(size 1.27 1.27)
					(thickness 0.15)
				)
				(justify left bottom)
				(hide yes)
			)
		)
		(property "Voltage" ""
			(at 163.83 200.66 0)
			(effects
				(font
					(size 1.27 1.27)
				)
				(justify left bottom)
				(hide yes)
			)
		)
		(property "Dielectric" ""
			(at 161.29 200.66 0)
			(effects
				(font
					(size 1.27 1.27)
				)
				(justify left bottom)
				(hide yes)
			)
		)
		(pin "1"
		)
		(pin "2"
		)
		(instances
			(project "k410t-devboard"
				(path ""
					(reference "C135")
					(unit 1)
				)
			)
		)
	)
	(symbol
		(lib_id "antmicroCapacitors0603:C_47u_0603")
		(at 153.67 220.98 270)
		(mirror x)
		(unit 1)
		(exclude_from_sim no)
		(in_bom yes)
		(on_board yes)
		(dnp no)
		(property "Reference" "C377"
			(at 153.035 216.535 90)
			(effects
				(font
					(size 1.27 1.27)
				)
				(justify right)
			)
		)
		(property "Value" "C_47u_0603"
			(at 143.51 200.66 0)
			(effects
				(font
					(size 1.27 1.27)
					(thickness 0.15)
				)
				(justify left bottom)
				(hide yes)
			)
		)
		(property "Footprint" "antmicro-footprints:C_0603_1608Metric"
			(at 140.97 200.66 0)
			(effects
				(font
					(size 1.27 1.27)
					(thickness 0.15)
				)
				(justify left bottom)
				(hide yes)
			)
		)
		(property "Datasheet" "https://www.murata.com/products/productdetail?partno=GRM188R60J476ME15%23"
			(at 138.43 200.66 0)
			(effects
				(font
					(size 1.27 1.27)
					(thickness 0.15)
				)
				(justify left bottom)
				(hide yes)
			)
		)
		(property "Description" ""
			(at 153.67 220.98 0)
			(effects
				(font
					(size 1.27 1.27)
				)
			)
		)
		(property "Manufacturer" "Murata"
			(at 133.35 200.66 0)
			(effects
				(font
					(size 1.27 1.27)
					(thickness 0.15)
				)
				(justify left bottom)
				(hide yes)
			)
		)
		(property "MPN" "GRM188R60J476ME15D"
			(at 135.89 200.66 0)
			(effects
				(font
					(size 1.27 1.27)
					(thickness 0.15)
				)
				(justify left bottom)
				(hide yes)
			)
		)
		(property "Val" "47u"
			(at 153.035 220.345 90)
			(effects
				(font
					(size 1.27 1.27)
					(thickness 0.15)
				)
				(justify right)
			)
		)
		(property "License" "Apache-2.0"
			(at 130.81 200.66 0)
			(effects
				(font
					(size 1.27 1.27)
					(thickness 0.15)
				)
				(justify left bottom)
				(hide yes)
			)
		)
		(property "Author" "Antmicro"
			(at 128.27 200.66 0)
			(effects
				(font
					(size 1.27 1.27)
					(thickness 0.15)
				)
				(justify left bottom)
				(hide yes)
			)
		)
		(property "Voltage" ""
			(at 125.73 200.66 0)
			(effects
				(font
					(size 1.27 1.27)
				)
				(justify left bottom)
				(hide yes)
			)
		)
		(property "Dielectric" ""
			(at 123.19 200.66 0)
			(effects
				(font
					(size 1.27 1.27)
				)
				(justify left bottom)
				(hide yes)
			)
		)
		(pin "1"
		)
		(pin "2"
		)
		(instances
			(project "k410t-devboard"
				(path ""
					(reference "C377")
					(unit 1)
				)
			)
		)
	)
	(symbol
		(lib_id "antmicropower:VCC_USR_B")
		(at 397.51 242.57 0)
		(mirror y)
		(unit 1)
		(exclude_from_sim no)
		(in_bom yes)
		(on_board yes)
		(dnp no)
		(fields_autoplaced yes)
		(property "Reference" "#PWR0430"
			(at 397.51 246.38 0)
			(effects
				(font
					(size 1.27 1.27)
				)
				(hide yes)
			)
		)
		(property "Value" "VCC_USR_B"
			(at 397.51 238.76 0)
			(effects
				(font
					(size 1.27 1.27)
				)
			)
		)
		(property "Footprint" ""
			(at 397.51 242.57 0)
			(effects
				(font
					(size 1.27 1.27)
				)
				(hide yes)
			)
		)
		(property "Datasheet" ""
			(at 397.51 242.57 0)
			(effects
				(font
					(size 1.27 1.27)
				)
				(hide yes)
			)
		)
		(property "Description" ""
			(at 397.51 242.57 0)
			(effects
				(font
					(size 1.27 1.27)
				)
			)
		)
		(pin "1"
		)
		(instances
			(project "k410t-devboard"
				(path ""
					(reference "#PWR0430")
					(unit 1)
				)
			)
		)
	)
	(symbol
		(lib_id "antmicroCapacitorsmisc:C_100n_0201")
		(at 165.1 76.2 90)
		(unit 1)
		(exclude_from_sim no)
		(in_bom yes)
		(on_board yes)
		(dnp no)
		(property "Reference" "C142"
			(at 165.735 71.755 90)
			(effects
				(font
					(size 1.27 1.27)
				)
				(justify right)
			)
		)
		(property "Value" "C_100n_0201"
			(at 175.26 55.88 0)
			(effects
				(font
					(size 1.27 1.27)
					(thickness 0.15)
				)
				(justify left bottom)
				(hide yes)
			)
		)
		(property "Footprint" "antmicro-footprints:C_0201"
			(at 177.8 55.88 0)
			(effects
				(font
					(size 1.27 1.27)
					(thickness 0.15)
				)
				(justify left bottom)
				(hide yes)
			)
		)
		(property "Datasheet" "https://www.yageo.com/en/Chart/Download/pdf/CC0201KRX6S5BB104"
			(at 180.34 55.88 0)
			(effects
				(font
					(size 1.27 1.27)
					(thickness 0.15)
				)
				(justify left bottom)
				(hide yes)
			)
		)
		(property "Description" ""
			(at 165.1 76.2 0)
			(effects
				(font
					(size 1.27 1.27)
				)
			)
		)
		(property "Manufacturer" "YAGEO"
			(at 185.42 55.88 0)
			(effects
				(font
					(size 1.27 1.27)
					(thickness 0.15)
				)
				(justify left bottom)
				(hide yes)
			)
		)
		(property "MPN" "CC0201KRX6S5BB104"
			(at 182.88 55.88 0)
			(effects
				(font
					(size 1.27 1.27)
					(thickness 0.15)
				)
				(justify left bottom)
				(hide yes)
			)
		)
		(property "Val" "100n"
			(at 165.735 75.565 90)
			(effects
				(font
					(size 1.27 1.27)
					(thickness 0.15)
				)
				(justify right)
			)
		)
		(property "License" "Apache-2.0"
			(at 187.96 55.88 0)
			(effects
				(font
					(size 1.27 1.27)
					(thickness 0.15)
				)
				(justify left bottom)
				(hide yes)
			)
		)
		(property "Author" "Antmicro"
			(at 190.5 55.88 0)
			(effects
				(font
					(size 1.27 1.27)
					(thickness 0.15)
				)
				(justify left bottom)
				(hide yes)
			)
		)
		(property "Voltage" ""
			(at 193.04 55.88 0)
			(effects
				(font
					(size 1.27 1.27)
				)
				(justify left bottom)
				(hide yes)
			)
		)
		(property "Dielectric" ""
			(at 195.58 55.88 0)
			(effects
				(font
					(size 1.27 1.27)
				)
				(justify left bottom)
				(hide yes)
			)
		)
		(pin "1"
		)
		(pin "2"
		)
		(instances
			(project "k410t-devboard"
				(path ""
					(reference "C142")
					(unit 1)
				)
			)
		)
	)
	(symbol
		(lib_id "antmicroCapacitorspol:C_Pol_330u_6.3V_KEMET-T520-B")
		(at 115.57 233.68 0)
		(mirror y)
		(unit 1)
		(exclude_from_sim no)
		(in_bom yes)
		(on_board yes)
		(dnp no)
		(property "Reference" "C125"
			(at 114.935 234.315 0)
			(effects
				(font
					(size 1.27 1.27)
				)
				(justify left)
			)
		)
		(property "Value" "C_Pol_330u_6.3V_KEMET-T520-B"
			(at 101.6 238.76 0)
			(effects
				(font
					(size 1.27 1.27)
					(thickness 0.15)
				)
				(justify left bottom)
				(hide yes)
			)
		)
		(property "Footprint" "antmicro-footprints:C_Pol_EIA-B"
			(at 101.6 241.3 0)
			(effects
				(font
					(size 1.27 1.27)
					(thickness 0.15)
				)
				(justify left bottom)
				(hide yes)
			)
		)
		(property "Datasheet" "https://content.kemet.com/datasheets/KEM_T2076_T52X-530.pdf"
			(at 101.6 243.84 0)
			(effects
				(font
					(size 1.27 1.27)
					(thickness 0.15)
				)
				(justify left bottom)
				(hide yes)
			)
		)
		(property "Description" ""
			(at 115.57 233.68 0)
			(effects
				(font
					(size 1.27 1.27)
				)
			)
		)
		(property "Manufacturer" "KEMET"
			(at 101.6 248.92 0)
			(effects
				(font
					(size 1.27 1.27)
					(thickness 0.15)
				)
				(justify left bottom)
				(hide yes)
			)
		)
		(property "MPN" "T520B337M006ATE040"
			(at 101.6 246.38 0)
			(effects
				(font
					(size 1.27 1.27)
					(thickness 0.15)
				)
				(justify left bottom)
				(hide yes)
			)
		)
		(property "Val" "330u"
			(at 114.935 238.76 0)
			(effects
				(font
					(size 1.27 1.27)
					(thickness 0.15)
				)
				(justify left)
			)
		)
		(property "License" "Apache-2.0"
			(at 101.6 251.46 0)
			(effects
				(font
					(size 1.27 1.27)
					(thickness 0.15)
				)
				(justify left bottom)
				(hide yes)
			)
		)
		(property "Author" "Antmicro"
			(at 101.6 254 0)
			(effects
				(font
					(size 1.27 1.27)
					(thickness 0.15)
				)
				(justify left bottom)
				(hide yes)
			)
		)
		(property "Voltage" "6.3V"
			(at 101.6 256.54 0)
			(effects
				(font
					(size 1.27 1.27)
				)
				(justify left bottom)
				(hide yes)
			)
		)
		(property "Dielectric" ""
			(at 101.6 259.08 0)
			(effects
				(font
					(size 1.27 1.27)
				)
				(justify left bottom)
				(hide yes)
			)
		)
		(pin "1"
		)
		(pin "2"
		)
		(instances
			(project "k410t-devboard"
				(path ""
					(reference "C125")
					(unit 1)
				)
			)
		)
	)
	(symbol
		(lib_id "antmicroCapacitorsmisc:C_4u7_0201")
		(at 180.34 36.83 90)
		(unit 1)
		(exclude_from_sim no)
		(in_bom yes)
		(on_board yes)
		(dnp no)
		(property "Reference" "C86"
			(at 180.975 32.385 90)
			(effects
				(font
					(size 1.27 1.27)
				)
				(justify right)
			)
		)
		(property "Value" "C_4u7_0201"
			(at 190.5 16.51 0)
			(effects
				(font
					(size 1.27 1.27)
					(thickness 0.15)
				)
				(justify left bottom)
				(hide yes)
			)
		)
		(property "Footprint" "antmicro-footprints:C_0201"
			(at 193.04 16.51 0)
			(effects
				(font
					(size 1.27 1.27)
					(thickness 0.15)
				)
				(justify left bottom)
				(hide yes)
			)
		)
		(property "Datasheet" "https://www.murata.com/products/productdetail?partno=GRM035R60J475ME15%23"
			(at 195.58 16.51 0)
			(effects
				(font
					(size 1.27 1.27)
					(thickness 0.15)
				)
				(justify left bottom)
				(hide yes)
			)
		)
		(property "Description" ""
			(at 180.34 36.83 0)
			(effects
				(font
					(size 1.27 1.27)
				)
			)
		)
		(property "Manufacturer" "Murata"
			(at 200.66 16.51 0)
			(effects
				(font
					(size 1.27 1.27)
					(thickness 0.15)
				)
				(justify left bottom)
				(hide yes)
			)
		)
		(property "MPN" "GRM035R60J475ME15D"
			(at 198.12 16.51 0)
			(effects
				(font
					(size 1.27 1.27)
					(thickness 0.15)
				)
				(justify left bottom)
				(hide yes)
			)
		)
		(property "Val" "4u7"
			(at 180.975 36.195 90)
			(effects
				(font
					(size 1.27 1.27)
					(thickness 0.15)
				)
				(justify right)
			)
		)
		(property "License" "Apache-2.0"
			(at 203.2 16.51 0)
			(effects
				(font
					(size 1.27 1.27)
					(thickness 0.15)
				)
				(justify left bottom)
				(hide yes)
			)
		)
		(property "Author" "Antmicro"
			(at 205.74 16.51 0)
			(effects
				(font
					(size 1.27 1.27)
					(thickness 0.15)
				)
				(justify left bottom)
				(hide yes)
			)
		)
		(property "Voltage" ""
			(at 208.28 16.51 0)
			(effects
				(font
					(size 1.27 1.27)
				)
				(justify left bottom)
				(hide yes)
			)
		)
		(property "Dielectric" ""
			(at 210.82 16.51 0)
			(effects
				(font
					(size 1.27 1.27)
				)
				(justify left bottom)
				(hide yes)
			)
		)
		(pin "1"
		)
		(pin "2"
		)
		(instances
			(project "k410t-devboard"
				(path ""
					(reference "C86")
					(unit 1)
				)
			)
		)
	)
	(symbol
		(lib_id "antmicroCapacitorsmisc:C_4u7_0201")
		(at 146.05 201.93 270)
		(mirror x)
		(unit 1)
		(exclude_from_sim no)
		(in_bom yes)
		(on_board yes)
		(dnp no)
		(property "Reference" "C52"
			(at 145.415 197.485 90)
			(effects
				(font
					(size 1.27 1.27)
				)
				(justify right)
			)
		)
		(property "Value" "C_4u7_0201"
			(at 135.89 181.61 0)
			(effects
				(font
					(size 1.27 1.27)
					(thickness 0.15)
				)
				(justify left bottom)
				(hide yes)
			)
		)
		(property "Footprint" "antmicro-footprints:C_0201"
			(at 133.35 181.61 0)
			(effects
				(font
					(size 1.27 1.27)
					(thickness 0.15)
				)
				(justify left bottom)
				(hide yes)
			)
		)
		(property "Datasheet" "https://www.murata.com/products/productdetail?partno=GRM035R60J475ME15%23"
			(at 130.81 181.61 0)
			(effects
				(font
					(size 1.27 1.27)
					(thickness 0.15)
				)
				(justify left bottom)
				(hide yes)
			)
		)
		(property "Description" ""
			(at 146.05 201.93 0)
			(effects
				(font
					(size 1.27 1.27)
				)
			)
		)
		(property "Manufacturer" "Murata"
			(at 125.73 181.61 0)
			(effects
				(font
					(size 1.27 1.27)
					(thickness 0.15)
				)
				(justify left bottom)
				(hide yes)
			)
		)
		(property "MPN" "GRM035R60J475ME15D"
			(at 128.27 181.61 0)
			(effects
				(font
					(size 1.27 1.27)
					(thickness 0.15)
				)
				(justify left bottom)
				(hide yes)
			)
		)
		(property "Val" "4u7"
			(at 145.415 201.295 90)
			(effects
				(font
					(size 1.27 1.27)
					(thickness 0.15)
				)
				(justify right)
			)
		)
		(property "License" "Apache-2.0"
			(at 123.19 181.61 0)
			(effects
				(font
					(size 1.27 1.27)
					(thickness 0.15)
				)
				(justify left bottom)
				(hide yes)
			)
		)
		(property "Author" "Antmicro"
			(at 120.65 181.61 0)
			(effects
				(font
					(size 1.27 1.27)
					(thickness 0.15)
				)
				(justify left bottom)
				(hide yes)
			)
		)
		(property "Voltage" ""
			(at 118.11 181.61 0)
			(effects
				(font
					(size 1.27 1.27)
				)
				(justify left bottom)
				(hide yes)
			)
		)
		(property "Dielectric" ""
			(at 115.57 181.61 0)
			(effects
				(font
					(size 1.27 1.27)
				)
				(justify left bottom)
				(hide yes)
			)
		)
		(pin "1"
		)
		(pin "2"
		)
		(instances
			(project "k410t-devboard"
				(path ""
					(reference "C52")
					(unit 1)
				)
			)
		)
	)
	(symbol
		(lib_id "antmicroCapacitorsmisc:C_4u7_0201")
		(at 191.77 201.93 270)
		(mirror x)
		(unit 1)
		(exclude_from_sim no)
		(in_bom yes)
		(on_board yes)
		(dnp no)
		(property "Reference" "C22"
			(at 191.135 197.485 90)
			(effects
				(font
					(size 1.27 1.27)
				)
				(justify right)
			)
		)
		(property "Value" "C_4u7_0201"
			(at 181.61 181.61 0)
			(effects
				(font
					(size 1.27 1.27)
					(thickness 0.15)
				)
				(justify left bottom)
				(hide yes)
			)
		)
		(property "Footprint" "antmicro-footprints:C_0201"
			(at 179.07 181.61 0)
			(effects
				(font
					(size 1.27 1.27)
					(thickness 0.15)
				)
				(justify left bottom)
				(hide yes)
			)
		)
		(property "Datasheet" "https://www.murata.com/products/productdetail?partno=GRM035R60J475ME15%23"
			(at 176.53 181.61 0)
			(effects
				(font
					(size 1.27 1.27)
					(thickness 0.15)
				)
				(justify left bottom)
				(hide yes)
			)
		)
		(property "Description" ""
			(at 191.77 201.93 0)
			(effects
				(font
					(size 1.27 1.27)
				)
			)
		)
		(property "Manufacturer" "Murata"
			(at 171.45 181.61 0)
			(effects
				(font
					(size 1.27 1.27)
					(thickness 0.15)
				)
				(justify left bottom)
				(hide yes)
			)
		)
		(property "MPN" "GRM035R60J475ME15D"
			(at 173.99 181.61 0)
			(effects
				(font
					(size 1.27 1.27)
					(thickness 0.15)
				)
				(justify left bottom)
				(hide yes)
			)
		)
		(property "Val" "4u7"
			(at 191.135 201.295 90)
			(effects
				(font
					(size 1.27 1.27)
					(thickness 0.15)
				)
				(justify right)
			)
		)
		(property "License" "Apache-2.0"
			(at 168.91 181.61 0)
			(effects
				(font
					(size 1.27 1.27)
					(thickness 0.15)
				)
				(justify left bottom)
				(hide yes)
			)
		)
		(property "Author" "Antmicro"
			(at 166.37 181.61 0)
			(effects
				(font
					(size 1.27 1.27)
					(thickness 0.15)
				)
				(justify left bottom)
				(hide yes)
			)
		)
		(property "Voltage" ""
			(at 163.83 181.61 0)
			(effects
				(font
					(size 1.27 1.27)
				)
				(justify left bottom)
				(hide yes)
			)
		)
		(property "Dielectric" ""
			(at 161.29 181.61 0)
			(effects
				(font
					(size 1.27 1.27)
				)
				(justify left bottom)
				(hide yes)
			)
		)
		(pin "1"
		)
		(pin "2"
		)
		(instances
			(project "k410t-devboard"
				(path ""
					(reference "C22")
					(unit 1)
				)
			)
		)
	)
	(symbol
		(lib_id "antmicroCapacitorsmisc:C_100n_0201")
		(at 218.44 76.2 90)
		(unit 1)
		(exclude_from_sim no)
		(in_bom yes)
		(on_board yes)
		(dnp no)
		(property "Reference" "C156"
			(at 219.075 71.755 90)
			(effects
				(font
					(size 1.27 1.27)
				)
				(justify right)
			)
		)
		(property "Value" "C_100n_0201"
			(at 228.6 55.88 0)
			(effects
				(font
					(size 1.27 1.27)
					(thickness 0.15)
				)
				(justify left bottom)
				(hide yes)
			)
		)
		(property "Footprint" "antmicro-footprints:C_0201"
			(at 231.14 55.88 0)
			(effects
				(font
					(size 1.27 1.27)
					(thickness 0.15)
				)
				(justify left bottom)
				(hide yes)
			)
		)
		(property "Datasheet" "https://www.yageo.com/en/Chart/Download/pdf/CC0201KRX6S5BB104"
			(at 233.68 55.88 0)
			(effects
				(font
					(size 1.27 1.27)
					(thickness 0.15)
				)
				(justify left bottom)
				(hide yes)
			)
		)
		(property "Description" ""
			(at 218.44 76.2 0)
			(effects
				(font
					(size 1.27 1.27)
				)
			)
		)
		(property "Manufacturer" "YAGEO"
			(at 238.76 55.88 0)
			(effects
				(font
					(size 1.27 1.27)
					(thickness 0.15)
				)
				(justify left bottom)
				(hide yes)
			)
		)
		(property "MPN" "CC0201KRX6S5BB104"
			(at 236.22 55.88 0)
			(effects
				(font
					(size 1.27 1.27)
					(thickness 0.15)
				)
				(justify left bottom)
				(hide yes)
			)
		)
		(property "Val" "100n"
			(at 219.075 75.565 90)
			(effects
				(font
					(size 1.27 1.27)
					(thickness 0.15)
				)
				(justify right)
			)
		)
		(property "License" "Apache-2.0"
			(at 241.3 55.88 0)
			(effects
				(font
					(size 1.27 1.27)
					(thickness 0.15)
				)
				(justify left bottom)
				(hide yes)
			)
		)
		(property "Author" "Antmicro"
			(at 243.84 55.88 0)
			(effects
				(font
					(size 1.27 1.27)
					(thickness 0.15)
				)
				(justify left bottom)
				(hide yes)
			)
		)
		(property "Voltage" ""
			(at 246.38 55.88 0)
			(effects
				(font
					(size 1.27 1.27)
				)
				(justify left bottom)
				(hide yes)
			)
		)
		(property "Dielectric" ""
			(at 248.92 55.88 0)
			(effects
				(font
					(size 1.27 1.27)
				)
				(justify left bottom)
				(hide yes)
			)
		)
		(pin "1"
		)
		(pin "2"
		)
		(instances
			(project "k410t-devboard"
				(path ""
					(reference "C156")
					(unit 1)
				)
			)
		)
	)
	(symbol
		(lib_id "antmicropower:+1V8")
		(at 383.54 238.76 0)
		(mirror y)
		(unit 1)
		(exclude_from_sim no)
		(in_bom yes)
		(on_board yes)
		(dnp no)
		(property "Reference" "#PWR0428"
			(at 383.54 242.57 0)
			(effects
				(font
					(size 1.27 1.27)
				)
				(hide yes)
			)
		)
		(property "Value" "+1V8"
			(at 383.54 235.204 0)
			(effects
				(font
					(size 1.27 1.27)
				)
			)
		)
		(property "Footprint" ""
			(at 368.3 246.38 0)
			(effects
				(font
					(size 1.27 1.27)
					(thickness 0.15)
				)
				(justify left bottom)
				(hide yes)
			)
		)
		(property "Datasheet" ""
			(at 368.3 248.92 0)
			(effects
				(font
					(size 1.27 1.27)
					(thickness 0.15)
				)
				(justify left bottom)
				(hide yes)
			)
		)
		(property "Description" ""
			(at 383.54 238.76 0)
			(effects
				(font
					(size 1.27 1.27)
				)
			)
		)
		(property "Author" "Antmicro"
			(at 368.3 246.38 0)
			(effects
				(font
					(size 1.27 1.27)
					(thickness 0.15)
				)
				(justify left bottom)
				(hide yes)
			)
		)
		(property "License" "Apache-2.0"
			(at 368.3 248.92 0)
			(effects
				(font
					(size 1.27 1.27)
					(thickness 0.15)
				)
				(justify left bottom)
				(hide yes)
			)
		)
		(pin "1"
		)
		(instances
			(project "k410t-devboard"
				(path ""
					(reference "#PWR0428")
					(unit 1)
				)
			)
		)
	)
	(symbol
		(lib_id "antmicropower:GND")
		(at 248.92 194.31 0)
		(unit 1)
		(exclude_from_sim no)
		(in_bom yes)
		(on_board yes)
		(dnp no)
		(property "Reference" "#PWR042"
			(at 248.92 200.66 0)
			(effects
				(font
					(size 1.27 1.27)
				)
				(hide yes)
			)
		)
		(property "Value" "GND"
			(at 248.92 198.12 0)
			(effects
				(font
					(size 1.27 1.27)
				)
			)
		)
		(property "Footprint" ""
			(at 257.81 201.93 0)
			(effects
				(font
					(size 1.27 1.27)
					(thickness 0.15)
				)
				(justify left bottom)
				(hide yes)
			)
		)
		(property "Datasheet" ""
			(at 257.81 207.01 0)
			(effects
				(font
					(size 1.27 1.27)
					(thickness 0.15)
				)
				(justify left bottom)
				(hide yes)
			)
		)
		(property "Description" ""
			(at 248.92 194.31 0)
			(effects
				(font
					(size 1.27 1.27)
				)
			)
		)
		(property "Author" "Antmicro"
			(at 257.81 201.93 0)
			(effects
				(font
					(size 1.27 1.27)
					(thickness 0.15)
				)
				(justify left bottom)
				(hide yes)
			)
		)
		(property "License" "Apache-2.0"
			(at 257.81 204.47 0)
			(effects
				(font
					(size 1.27 1.27)
					(thickness 0.15)
				)
				(justify left bottom)
				(hide yes)
			)
		)
		(pin "1"
		)
		(instances
			(project "k410t-devboard"
				(path ""
					(reference "#PWR042")
					(unit 1)
				)
			)
		)
	)
	(symbol
		(lib_id "antmicroCapacitorsmisc:C_4u7_0201")
		(at 199.39 201.93 270)
		(mirror x)
		(unit 1)
		(exclude_from_sim no)
		(in_bom yes)
		(on_board yes)
		(dnp no)
		(property "Reference" "C9"
			(at 198.755 197.485 90)
			(effects
				(font
					(size 1.27 1.27)
				)
				(justify right)
			)
		)
		(property "Value" "C_4u7_0201"
			(at 189.23 181.61 0)
			(effects
				(font
					(size 1.27 1.27)
					(thickness 0.15)
				)
				(justify left bottom)
				(hide yes)
			)
		)
		(property "Footprint" "antmicro-footprints:C_0201"
			(at 186.69 181.61 0)
			(effects
				(font
					(size 1.27 1.27)
					(thickness 0.15)
				)
				(justify left bottom)
				(hide yes)
			)
		)
		(property "Datasheet" "https://www.murata.com/products/productdetail?partno=GRM035R60J475ME15%23"
			(at 184.15 181.61 0)
			(effects
				(font
					(size 1.27 1.27)
					(thickness 0.15)
				)
				(justify left bottom)
				(hide yes)
			)
		)
		(property "Description" ""
			(at 199.39 201.93 0)
			(effects
				(font
					(size 1.27 1.27)
				)
			)
		)
		(property "Manufacturer" "Murata"
			(at 179.07 181.61 0)
			(effects
				(font
					(size 1.27 1.27)
					(thickness 0.15)
				)
				(justify left bottom)
				(hide yes)
			)
		)
		(property "MPN" "GRM035R60J475ME15D"
			(at 181.61 181.61 0)
			(effects
				(font
					(size 1.27 1.27)
					(thickness 0.15)
				)
				(justify left bottom)
				(hide yes)
			)
		)
		(property "Val" "4u7"
			(at 198.755 201.295 90)
			(effects
				(font
					(size 1.27 1.27)
					(thickness 0.15)
				)
				(justify right)
			)
		)
		(property "License" "Apache-2.0"
			(at 176.53 181.61 0)
			(effects
				(font
					(size 1.27 1.27)
					(thickness 0.15)
				)
				(justify left bottom)
				(hide yes)
			)
		)
		(property "Author" "Antmicro"
			(at 173.99 181.61 0)
			(effects
				(font
					(size 1.27 1.27)
					(thickness 0.15)
				)
				(justify left bottom)
				(hide yes)
			)
		)
		(property "Voltage" ""
			(at 171.45 181.61 0)
			(effects
				(font
					(size 1.27 1.27)
				)
				(justify left bottom)
				(hide yes)
			)
		)
		(property "Dielectric" ""
			(at 168.91 181.61 0)
			(effects
				(font
					(size 1.27 1.27)
				)
				(justify left bottom)
				(hide yes)
			)
		)
		(pin "1"
		)
		(pin "2"
		)
		(instances
			(project "k410t-devboard"
				(path ""
					(reference "C9")
					(unit 1)
				)
			)
		)
	)
	(symbol
		(lib_id "antmicroCapacitors0603:C_47u_0603")
		(at 130.81 220.98 270)
		(mirror x)
		(unit 1)
		(exclude_from_sim no)
		(in_bom yes)
		(on_board yes)
		(dnp no)
		(property "Reference" "C380"
			(at 130.175 216.535 90)
			(effects
				(font
					(size 1.27 1.27)
				)
				(justify right)
			)
		)
		(property "Value" "C_47u_0603"
			(at 120.65 200.66 0)
			(effects
				(font
					(size 1.27 1.27)
					(thickness 0.15)
				)
				(justify left bottom)
				(hide yes)
			)
		)
		(property "Footprint" "antmicro-footprints:C_0603_1608Metric"
			(at 118.11 200.66 0)
			(effects
				(font
					(size 1.27 1.27)
					(thickness 0.15)
				)
				(justify left bottom)
				(hide yes)
			)
		)
		(property "Datasheet" "https://www.murata.com/products/productdetail?partno=GRM188R60J476ME15%23"
			(at 115.57 200.66 0)
			(effects
				(font
					(size 1.27 1.27)
					(thickness 0.15)
				)
				(justify left bottom)
				(hide yes)
			)
		)
		(property "Description" ""
			(at 130.81 220.98 0)
			(effects
				(font
					(size 1.27 1.27)
				)
			)
		)
		(property "Manufacturer" "Murata"
			(at 110.49 200.66 0)
			(effects
				(font
					(size 1.27 1.27)
					(thickness 0.15)
				)
				(justify left bottom)
				(hide yes)
			)
		)
		(property "MPN" "GRM188R60J476ME15D"
			(at 113.03 200.66 0)
			(effects
				(font
					(size 1.27 1.27)
					(thickness 0.15)
				)
				(justify left bottom)
				(hide yes)
			)
		)
		(property "Val" "47u"
			(at 130.175 220.345 90)
			(effects
				(font
					(size 1.27 1.27)
					(thickness 0.15)
				)
				(justify right)
			)
		)
		(property "License" "Apache-2.0"
			(at 107.95 200.66 0)
			(effects
				(font
					(size 1.27 1.27)
					(thickness 0.15)
				)
				(justify left bottom)
				(hide yes)
			)
		)
		(property "Author" "Antmicro"
			(at 105.41 200.66 0)
			(effects
				(font
					(size 1.27 1.27)
					(thickness 0.15)
				)
				(justify left bottom)
				(hide yes)
			)
		)
		(property "Voltage" ""
			(at 102.87 200.66 0)
			(effects
				(font
					(size 1.27 1.27)
				)
				(justify left bottom)
				(hide yes)
			)
		)
		(property "Dielectric" ""
			(at 100.33 200.66 0)
			(effects
				(font
					(size 1.27 1.27)
				)
				(justify left bottom)
				(hide yes)
			)
		)
		(pin "1"
		)
		(pin "2"
		)
		(instances
			(project "k410t-devboard"
				(path ""
					(reference "C380")
					(unit 1)
				)
			)
		)
	)
	(symbol
		(lib_id "antmicroCapacitorsmisc:C_100n_0201")
		(at 187.96 31.75 90)
		(mirror x)
		(unit 1)
		(exclude_from_sim no)
		(in_bom yes)
		(on_board yes)
		(dnp no)
		(property "Reference" "C97"
			(at 188.595 32.385 90)
			(effects
				(font
					(size 1.27 1.27)
				)
				(justify right)
			)
		)
		(property "Value" "C_100n_0201"
			(at 198.12 52.07 0)
			(effects
				(font
					(size 1.27 1.27)
					(thickness 0.15)
				)
				(justify left bottom)
				(hide yes)
			)
		)
		(property "Footprint" "antmicro-footprints:C_0201"
			(at 200.66 52.07 0)
			(effects
				(font
					(size 1.27 1.27)
					(thickness 0.15)
				)
				(justify left bottom)
				(hide yes)
			)
		)
		(property "Datasheet" "https://www.yageo.com/en/Chart/Download/pdf/CC0201KRX6S5BB104"
			(at 203.2 52.07 0)
			(effects
				(font
					(size 1.27 1.27)
					(thickness 0.15)
				)
				(justify left bottom)
				(hide yes)
			)
		)
		(property "Description" ""
			(at 187.96 31.75 0)
			(effects
				(font
					(size 1.27 1.27)
				)
			)
		)
		(property "Manufacturer" "YAGEO"
			(at 208.28 52.07 0)
			(effects
				(font
					(size 1.27 1.27)
					(thickness 0.15)
				)
				(justify left bottom)
				(hide yes)
			)
		)
		(property "MPN" "CC0201KRX6S5BB104"
			(at 205.74 52.07 0)
			(effects
				(font
					(size 1.27 1.27)
					(thickness 0.15)
				)
				(justify left bottom)
				(hide yes)
			)
		)
		(property "Val" "100n"
			(at 188.595 36.195 90)
			(effects
				(font
					(size 1.27 1.27)
					(thickness 0.15)
				)
				(justify right)
			)
		)
		(property "License" "Apache-2.0"
			(at 210.82 52.07 0)
			(effects
				(font
					(size 1.27 1.27)
					(thickness 0.15)
				)
				(justify left bottom)
				(hide yes)
			)
		)
		(property "Author" "Antmicro"
			(at 213.36 52.07 0)
			(effects
				(font
					(size 1.27 1.27)
					(thickness 0.15)
				)
				(justify left bottom)
				(hide yes)
			)
		)
		(property "Voltage" ""
			(at 215.9 52.07 0)
			(effects
				(font
					(size 1.27 1.27)
				)
				(justify left bottom)
				(hide yes)
			)
		)
		(property "Dielectric" ""
			(at 218.44 52.07 0)
			(effects
				(font
					(size 1.27 1.27)
				)
				(justify left bottom)
				(hide yes)
			)
		)
		(pin "1"
		)
		(pin "2"
		)
		(instances
			(project "k410t-devboard"
				(path ""
					(reference "C97")
					(unit 1)
				)
			)
		)
	)
	(symbol
		(lib_id "antmicroCapacitorsmisc:C_100n_0201")
		(at 218.44 31.75 90)
		(mirror x)
		(unit 1)
		(exclude_from_sim no)
		(in_bom yes)
		(on_board yes)
		(dnp no)
		(property "Reference" "C115"
			(at 219.075 32.385 90)
			(effects
				(font
					(size 1.27 1.27)
				)
				(justify right)
			)
		)
		(property "Value" "C_100n_0201"
			(at 228.6 52.07 0)
			(effects
				(font
					(size 1.27 1.27)
					(thickness 0.15)
				)
				(justify left bottom)
				(hide yes)
			)
		)
		(property "Footprint" "antmicro-footprints:C_0201"
			(at 231.14 52.07 0)
			(effects
				(font
					(size 1.27 1.27)
					(thickness 0.15)
				)
				(justify left bottom)
				(hide yes)
			)
		)
		(property "Datasheet" "https://www.yageo.com/en/Chart/Download/pdf/CC0201KRX6S5BB104"
			(at 233.68 52.07 0)
			(effects
				(font
					(size 1.27 1.27)
					(thickness 0.15)
				)
				(justify left bottom)
				(hide yes)
			)
		)
		(property "Description" ""
			(at 218.44 31.75 0)
			(effects
				(font
					(size 1.27 1.27)
				)
			)
		)
		(property "Manufacturer" "YAGEO"
			(at 238.76 52.07 0)
			(effects
				(font
					(size 1.27 1.27)
					(thickness 0.15)
				)
				(justify left bottom)
				(hide yes)
			)
		)
		(property "MPN" "CC0201KRX6S5BB104"
			(at 236.22 52.07 0)
			(effects
				(font
					(size 1.27 1.27)
					(thickness 0.15)
				)
				(justify left bottom)
				(hide yes)
			)
		)
		(property "Val" "100n"
			(at 219.075 36.195 90)
			(effects
				(font
					(size 1.27 1.27)
					(thickness 0.15)
				)
				(justify right)
			)
		)
		(property "License" "Apache-2.0"
			(at 241.3 52.07 0)
			(effects
				(font
					(size 1.27 1.27)
					(thickness 0.15)
				)
				(justify left bottom)
				(hide yes)
			)
		)
		(property "Author" "Antmicro"
			(at 243.84 52.07 0)
			(effects
				(font
					(size 1.27 1.27)
					(thickness 0.15)
				)
				(justify left bottom)
				(hide yes)
			)
		)
		(property "Voltage" ""
			(at 246.38 52.07 0)
			(effects
				(font
					(size 1.27 1.27)
				)
				(justify left bottom)
				(hide yes)
			)
		)
		(property "Dielectric" ""
			(at 248.92 52.07 0)
			(effects
				(font
					(size 1.27 1.27)
				)
				(justify left bottom)
				(hide yes)
			)
		)
		(pin "1"
		)
		(pin "2"
		)
		(instances
			(project "k410t-devboard"
				(path ""
					(reference "C115")
					(unit 1)
				)
			)
		)
	)
	(symbol
		(lib_id "antmicroCapacitorsmisc:C_100n_0201")
		(at 176.53 220.98 270)
		(mirror x)
		(unit 1)
		(exclude_from_sim no)
		(in_bom yes)
		(on_board yes)
		(dnp no)
		(property "Reference" "C139"
			(at 175.895 216.535 90)
			(effects
				(font
					(size 1.27 1.27)
				)
				(justify right)
			)
		)
		(property "Value" "C_100n_0201"
			(at 166.37 200.66 0)
			(effects
				(font
					(size 1.27 1.27)
					(thickness 0.15)
				)
				(justify left bottom)
				(hide yes)
			)
		)
		(property "Footprint" "antmicro-footprints:C_0201"
			(at 163.83 200.66 0)
			(effects
				(font
					(size 1.27 1.27)
					(thickness 0.15)
				)
				(justify left bottom)
				(hide yes)
			)
		)
		(property "Datasheet" "https://www.yageo.com/en/Chart/Download/pdf/CC0201KRX6S5BB104"
			(at 161.29 200.66 0)
			(effects
				(font
					(size 1.27 1.27)
					(thickness 0.15)
				)
				(justify left bottom)
				(hide yes)
			)
		)
		(property "Description" ""
			(at 176.53 220.98 0)
			(effects
				(font
					(size 1.27 1.27)
				)
			)
		)
		(property "Manufacturer" "YAGEO"
			(at 156.21 200.66 0)
			(effects
				(font
					(size 1.27 1.27)
					(thickness 0.15)
				)
				(justify left bottom)
				(hide yes)
			)
		)
		(property "MPN" "CC0201KRX6S5BB104"
			(at 158.75 200.66 0)
			(effects
				(font
					(size 1.27 1.27)
					(thickness 0.15)
				)
				(justify left bottom)
				(hide yes)
			)
		)
		(property "Val" "100n"
			(at 175.895 220.345 90)
			(effects
				(font
					(size 1.27 1.27)
					(thickness 0.15)
				)
				(justify right)
			)
		)
		(property "License" "Apache-2.0"
			(at 153.67 200.66 0)
			(effects
				(font
					(size 1.27 1.27)
					(thickness 0.15)
				)
				(justify left bottom)
				(hide yes)
			)
		)
		(property "Author" "Antmicro"
			(at 151.13 200.66 0)
			(effects
				(font
					(size 1.27 1.27)
					(thickness 0.15)
				)
				(justify left bottom)
				(hide yes)
			)
		)
		(property "Voltage" ""
			(at 148.59 200.66 0)
			(effects
				(font
					(size 1.27 1.27)
				)
				(justify left bottom)
				(hide yes)
			)
		)
		(property "Dielectric" ""
			(at 146.05 200.66 0)
			(effects
				(font
					(size 1.27 1.27)
				)
				(justify left bottom)
				(hide yes)
			)
		)
		(pin "1"
		)
		(pin "2"
		)
		(instances
			(project "k410t-devboard"
				(path ""
					(reference "C139")
					(unit 1)
				)
			)
		)
	)
	(symbol
		(lib_id "antmicroCapacitorsmisc:C_100n_0201")
		(at 184.15 220.98 270)
		(mirror x)
		(unit 1)
		(exclude_from_sim no)
		(in_bom yes)
		(on_board yes)
		(dnp no)
		(property "Reference" "C137"
			(at 183.515 216.535 90)
			(effects
				(font
					(size 1.27 1.27)
				)
				(justify right)
			)
		)
		(property "Value" "C_100n_0201"
			(at 173.99 200.66 0)
			(effects
				(font
					(size 1.27 1.27)
					(thickness 0.15)
				)
				(justify left bottom)
				(hide yes)
			)
		)
		(property "Footprint" "antmicro-footprints:C_0201"
			(at 171.45 200.66 0)
			(effects
				(font
					(size 1.27 1.27)
					(thickness 0.15)
				)
				(justify left bottom)
				(hide yes)
			)
		)
		(property "Datasheet" "https://www.yageo.com/en/Chart/Download/pdf/CC0201KRX6S5BB104"
			(at 168.91 200.66 0)
			(effects
				(font
					(size 1.27 1.27)
					(thickness 0.15)
				)
				(justify left bottom)
				(hide yes)
			)
		)
		(property "Description" ""
			(at 184.15 220.98 0)
			(effects
				(font
					(size 1.27 1.27)
				)
			)
		)
		(property "Manufacturer" "YAGEO"
			(at 163.83 200.66 0)
			(effects
				(font
					(size 1.27 1.27)
					(thickness 0.15)
				)
				(justify left bottom)
				(hide yes)
			)
		)
		(property "MPN" "CC0201KRX6S5BB104"
			(at 166.37 200.66 0)
			(effects
				(font
					(size 1.27 1.27)
					(thickness 0.15)
				)
				(justify left bottom)
				(hide yes)
			)
		)
		(property "Val" "100n"
			(at 183.515 220.345 90)
			(effects
				(font
					(size 1.27 1.27)
					(thickness 0.15)
				)
				(justify right)
			)
		)
		(property "License" "Apache-2.0"
			(at 161.29 200.66 0)
			(effects
				(font
					(size 1.27 1.27)
					(thickness 0.15)
				)
				(justify left bottom)
				(hide yes)
			)
		)
		(property "Author" "Antmicro"
			(at 158.75 200.66 0)
			(effects
				(font
					(size 1.27 1.27)
					(thickness 0.15)
				)
				(justify left bottom)
				(hide yes)
			)
		)
		(property "Voltage" ""
			(at 156.21 200.66 0)
			(effects
				(font
					(size 1.27 1.27)
				)
				(justify left bottom)
				(hide yes)
			)
		)
		(property "Dielectric" ""
			(at 153.67 200.66 0)
			(effects
				(font
					(size 1.27 1.27)
				)
				(justify left bottom)
				(hide yes)
			)
		)
		(pin "1"
		)
		(pin "2"
		)
		(instances
			(project "k410t-devboard"
				(path ""
					(reference "C137")
					(unit 1)
				)
			)
		)
	)
	(symbol
		(lib_id "antmicroCapacitorspol:C_Pol_330u_6.3V_KEMET-T520-B")
		(at 100.33 233.68 0)
		(mirror y)
		(unit 1)
		(exclude_from_sim no)
		(in_bom yes)
		(on_board yes)
		(dnp no)
		(property "Reference" "C133"
			(at 99.695 234.315 0)
			(effects
				(font
					(size 1.27 1.27)
				)
				(justify left)
			)
		)
		(property "Value" "C_Pol_330u_6.3V_KEMET-T520-B"
			(at 86.36 238.76 0)
			(effects
				(font
					(size 1.27 1.27)
					(thickness 0.15)
				)
				(justify left bottom)
				(hide yes)
			)
		)
		(property "Footprint" "antmicro-footprints:C_Pol_EIA-B"
			(at 86.36 241.3 0)
			(effects
				(font
					(size 1.27 1.27)
					(thickness 0.15)
				)
				(justify left bottom)
				(hide yes)
			)
		)
		(property "Datasheet" "https://content.kemet.com/datasheets/KEM_T2076_T52X-530.pdf"
			(at 86.36 243.84 0)
			(effects
				(font
					(size 1.27 1.27)
					(thickness 0.15)
				)
				(justify left bottom)
				(hide yes)
			)
		)
		(property "Description" ""
			(at 100.33 233.68 0)
			(effects
				(font
					(size 1.27 1.27)
				)
			)
		)
		(property "Manufacturer" "KEMET"
			(at 86.36 248.92 0)
			(effects
				(font
					(size 1.27 1.27)
					(thickness 0.15)
				)
				(justify left bottom)
				(hide yes)
			)
		)
		(property "MPN" "T520B337M006ATE040"
			(at 86.36 246.38 0)
			(effects
				(font
					(size 1.27 1.27)
					(thickness 0.15)
				)
				(justify left bottom)
				(hide yes)
			)
		)
		(property "Val" "330u"
			(at 99.695 238.76 0)
			(effects
				(font
					(size 1.27 1.27)
					(thickness 0.15)
				)
				(justify left)
			)
		)
		(property "License" "Apache-2.0"
			(at 86.36 251.46 0)
			(effects
				(font
					(size 1.27 1.27)
					(thickness 0.15)
				)
				(justify left bottom)
				(hide yes)
			)
		)
		(property "Author" "Antmicro"
			(at 86.36 254 0)
			(effects
				(font
					(size 1.27 1.27)
					(thickness 0.15)
				)
				(justify left bottom)
				(hide yes)
			)
		)
		(property "Voltage" "6.3V"
			(at 86.36 256.54 0)
			(effects
				(font
					(size 1.27 1.27)
				)
				(justify left bottom)
				(hide yes)
			)
		)
		(property "Dielectric" ""
			(at 86.36 259.08 0)
			(effects
				(font
					(size 1.27 1.27)
				)
				(justify left bottom)
				(hide yes)
			)
		)
		(pin "1"
		)
		(pin "2"
		)
		(instances
			(project "k410t-devboard"
				(path ""
					(reference "C133")
					(unit 1)
				)
			)
		)
	)
	(symbol
		(lib_id "antmicropower:+1V8")
		(at 219.71 44.45 0)
		(mirror y)
		(unit 1)
		(exclude_from_sim no)
		(in_bom yes)
		(on_board yes)
		(dnp no)
		(property "Reference" "#PWR026"
			(at 219.71 48.26 0)
			(effects
				(font
					(size 1.27 1.27)
				)
				(hide yes)
			)
		)
		(property "Value" "+1V8"
			(at 219.71 40.894 0)
			(effects
				(font
					(size 1.27 1.27)
				)
			)
		)
		(property "Footprint" ""
			(at 204.47 52.07 0)
			(effects
				(font
					(size 1.27 1.27)
					(thickness 0.15)
				)
				(justify left bottom)
				(hide yes)
			)
		)
		(property "Datasheet" ""
			(at 204.47 54.61 0)
			(effects
				(font
					(size 1.27 1.27)
					(thickness 0.15)
				)
				(justify left bottom)
				(hide yes)
			)
		)
		(property "Description" ""
			(at 219.71 44.45 0)
			(effects
				(font
					(size 1.27 1.27)
				)
			)
		)
		(property "Author" "Antmicro"
			(at 204.47 52.07 0)
			(effects
				(font
					(size 1.27 1.27)
					(thickness 0.15)
				)
				(justify left bottom)
				(hide yes)
			)
		)
		(property "License" "Apache-2.0"
			(at 204.47 54.61 0)
			(effects
				(font
					(size 1.27 1.27)
					(thickness 0.15)
				)
				(justify left bottom)
				(hide yes)
			)
		)
		(pin "1"
		)
		(instances
			(project "k410t-devboard"
				(path ""
					(reference "#PWR026")
					(unit 1)
				)
			)
		)
	)
	(symbol
		(lib_id "antmicroCapacitors0402:C_100n_0402")
		(at 219.71 48.26 270)
		(unit 1)
		(exclude_from_sim no)
		(in_bom yes)
		(on_board yes)
		(dnp no)
		(property "Reference" "C123"
			(at 219.075 48.895 90)
			(effects
				(font
					(size 1.27 1.27)
				)
				(justify right)
			)
		)
		(property "Value" "C_100n_0402"
			(at 209.55 68.58 0)
			(effects
				(font
					(size 1.27 1.27)
					(thickness 0.15)
				)
				(justify left bottom)
				(hide yes)
			)
		)
		(property "Footprint" "antmicro-footprints:C_0402_1005Metric"
			(at 207.01 68.58 0)
			(effects
				(font
					(size 1.27 1.27)
					(thickness 0.15)
				)
				(justify left bottom)
				(hide yes)
			)
		)
		(property "Datasheet" "https://www.murata.com/products/productdetail?partno=GRM155R61H104KE14%23"
			(at 204.47 68.58 0)
			(effects
				(font
					(size 1.27 1.27)
					(thickness 0.15)
				)
				(justify left bottom)
				(hide yes)
			)
		)
		(property "Description" ""
			(at 219.71 48.26 0)
			(effects
				(font
					(size 1.27 1.27)
				)
			)
		)
		(property "Manufacturer" "Murata"
			(at 199.39 68.58 0)
			(effects
				(font
					(size 1.27 1.27)
					(thickness 0.15)
				)
				(justify left bottom)
				(hide yes)
			)
		)
		(property "MPN" "GRM155R61H104KE14D"
			(at 201.93 68.58 0)
			(effects
				(font
					(size 1.27 1.27)
					(thickness 0.15)
				)
				(justify left bottom)
				(hide yes)
			)
		)
		(property "Val" "100n"
			(at 219.075 52.705 90)
			(effects
				(font
					(size 1.27 1.27)
					(thickness 0.15)
				)
				(justify right)
			)
		)
		(property "License" "Apache-2.0"
			(at 196.85 68.58 0)
			(effects
				(font
					(size 1.27 1.27)
					(thickness 0.15)
				)
				(justify left bottom)
				(hide yes)
			)
		)
		(property "Author" "Antmicro"
			(at 194.31 68.58 0)
			(effects
				(font
					(size 1.27 1.27)
					(thickness 0.15)
				)
				(justify left bottom)
				(hide yes)
			)
		)
		(property "Voltage" "50V"
			(at 191.77 68.58 0)
			(effects
				(font
					(size 1.27 1.27)
				)
				(justify left bottom)
				(hide yes)
			)
		)
		(property "Dielectric" "X5R"
			(at 189.23 68.58 0)
			(effects
				(font
					(size 1.27 1.27)
				)
				(justify left bottom)
				(hide yes)
			)
		)
		(pin "1"
		)
		(pin "2"
		)
		(instances
			(project "k410t-devboard"
				(path ""
					(reference "C123")
					(unit 1)
				)
			)
		)
	)
	(symbol
		(lib_id "antmicropower:+1V2_MGTAVTT")
		(at 139.7 67.31 0)
		(unit 1)
		(exclude_from_sim no)
		(in_bom yes)
		(on_board yes)
		(dnp no)
		(property "Reference" "#PWR0499"
			(at 139.7 71.12 0)
			(effects
				(font
					(size 1.27 1.27)
				)
				(hide yes)
			)
		)
		(property "Value" "+1V2_MGTAVTT"
			(at 139.7 63.5 0)
			(effects
				(font
					(size 1.27 1.27)
				)
			)
		)
		(property "Footprint" ""
			(at 139.7 67.31 0)
			(effects
				(font
					(size 1.27 1.27)
				)
				(hide yes)
			)
		)
		(property "Datasheet" ""
			(at 139.7 67.31 0)
			(effects
				(font
					(size 1.27 1.27)
				)
				(hide yes)
			)
		)
		(property "Description" ""
			(at 139.7 67.31 0)
			(effects
				(font
					(size 1.27 1.27)
				)
			)
		)
		(pin "1"
		)
		(instances
			(project "k410t-devboard"
				(path ""
					(reference "#PWR0499")
					(unit 1)
				)
			)
		)
	)
	(symbol
		(lib_id "antmicroCapacitorsmisc:C_100n_0201")
		(at 207.01 220.98 270)
		(mirror x)
		(unit 1)
		(exclude_from_sim no)
		(in_bom yes)
		(on_board yes)
		(dnp no)
		(property "Reference" "C129"
			(at 206.375 216.535 90)
			(effects
				(font
					(size 1.27 1.27)
				)
				(justify right)
			)
		)
		(property "Value" "C_100n_0201"
			(at 196.85 200.66 0)
			(effects
				(font
					(size 1.27 1.27)
					(thickness 0.15)
				)
				(justify left bottom)
				(hide yes)
			)
		)
		(property "Footprint" "antmicro-footprints:C_0201"
			(at 194.31 200.66 0)
			(effects
				(font
					(size 1.27 1.27)
					(thickness 0.15)
				)
				(justify left bottom)
				(hide yes)
			)
		)
		(property "Datasheet" "https://www.yageo.com/en/Chart/Download/pdf/CC0201KRX6S5BB104"
			(at 191.77 200.66 0)
			(effects
				(font
					(size 1.27 1.27)
					(thickness 0.15)
				)
				(justify left bottom)
				(hide yes)
			)
		)
		(property "Description" ""
			(at 207.01 220.98 0)
			(effects
				(font
					(size 1.27 1.27)
				)
			)
		)
		(property "Manufacturer" "YAGEO"
			(at 186.69 200.66 0)
			(effects
				(font
					(size 1.27 1.27)
					(thickness 0.15)
				)
				(justify left bottom)
				(hide yes)
			)
		)
		(property "MPN" "CC0201KRX6S5BB104"
			(at 189.23 200.66 0)
			(effects
				(font
					(size 1.27 1.27)
					(thickness 0.15)
				)
				(justify left bottom)
				(hide yes)
			)
		)
		(property "Val" "100n"
			(at 206.375 220.345 90)
			(effects
				(font
					(size 1.27 1.27)
					(thickness 0.15)
				)
				(justify right)
			)
		)
		(property "License" "Apache-2.0"
			(at 184.15 200.66 0)
			(effects
				(font
					(size 1.27 1.27)
					(thickness 0.15)
				)
				(justify left bottom)
				(hide yes)
			)
		)
		(property "Author" "Antmicro"
			(at 181.61 200.66 0)
			(effects
				(font
					(size 1.27 1.27)
					(thickness 0.15)
				)
				(justify left bottom)
				(hide yes)
			)
		)
		(property "Voltage" ""
			(at 179.07 200.66 0)
			(effects
				(font
					(size 1.27 1.27)
				)
				(justify left bottom)
				(hide yes)
			)
		)
		(property "Dielectric" ""
			(at 176.53 200.66 0)
			(effects
				(font
					(size 1.27 1.27)
				)
				(justify left bottom)
				(hide yes)
			)
		)
		(pin "1"
		)
		(pin "2"
		)
		(instances
			(project "k410t-devboard"
				(path ""
					(reference "C129")
					(unit 1)
				)
			)
		)
	)
	(symbol
		(lib_id "antmicroCapacitorspol:C_Pol_330u_6.3V_KEMET-T520-B")
		(at 107.95 233.68 0)
		(mirror y)
		(unit 1)
		(exclude_from_sim no)
		(in_bom yes)
		(on_board yes)
		(dnp no)
		(property "Reference" "C130"
			(at 107.315 234.315 0)
			(effects
				(font
					(size 1.27 1.27)
				)
				(justify left)
			)
		)
		(property "Value" "C_Pol_330u_6.3V_KEMET-T520-B"
			(at 93.98 238.76 0)
			(effects
				(font
					(size 1.27 1.27)
					(thickness 0.15)
				)
				(justify left bottom)
				(hide yes)
			)
		)
		(property "Footprint" "antmicro-footprints:C_Pol_EIA-B"
			(at 93.98 241.3 0)
			(effects
				(font
					(size 1.27 1.27)
					(thickness 0.15)
				)
				(justify left bottom)
				(hide yes)
			)
		)
		(property "Datasheet" "https://content.kemet.com/datasheets/KEM_T2076_T52X-530.pdf"
			(at 93.98 243.84 0)
			(effects
				(font
					(size 1.27 1.27)
					(thickness 0.15)
				)
				(justify left bottom)
				(hide yes)
			)
		)
		(property "Description" ""
			(at 107.95 233.68 0)
			(effects
				(font
					(size 1.27 1.27)
				)
			)
		)
		(property "Manufacturer" "KEMET"
			(at 93.98 248.92 0)
			(effects
				(font
					(size 1.27 1.27)
					(thickness 0.15)
				)
				(justify left bottom)
				(hide yes)
			)
		)
		(property "MPN" "T520B337M006ATE040"
			(at 93.98 246.38 0)
			(effects
				(font
					(size 1.27 1.27)
					(thickness 0.15)
				)
				(justify left bottom)
				(hide yes)
			)
		)
		(property "Val" "330u"
			(at 107.315 238.76 0)
			(effects
				(font
					(size 1.27 1.27)
					(thickness 0.15)
				)
				(justify left)
			)
		)
		(property "License" "Apache-2.0"
			(at 93.98 251.46 0)
			(effects
				(font
					(size 1.27 1.27)
					(thickness 0.15)
				)
				(justify left bottom)
				(hide yes)
			)
		)
		(property "Author" "Antmicro"
			(at 93.98 254 0)
			(effects
				(font
					(size 1.27 1.27)
					(thickness 0.15)
				)
				(justify left bottom)
				(hide yes)
			)
		)
		(property "Voltage" "6.3V"
			(at 93.98 256.54 0)
			(effects
				(font
					(size 1.27 1.27)
				)
				(justify left bottom)
				(hide yes)
			)
		)
		(property "Dielectric" ""
			(at 93.98 259.08 0)
			(effects
				(font
					(size 1.27 1.27)
				)
				(justify left bottom)
				(hide yes)
			)
		)
		(pin "1"
		)
		(pin "2"
		)
		(instances
			(project "k410t-devboard"
				(path ""
					(reference "C130")
					(unit 1)
				)
			)
		)
	)
	(symbol
		(lib_id "antmicroCapacitorsmisc:C_100n_0201")
		(at 195.58 93.98 90)
		(unit 1)
		(exclude_from_sim no)
		(in_bom yes)
		(on_board yes)
		(dnp no)
		(property "Reference" "C149"
			(at 196.215 89.535 90)
			(effects
				(font
					(size 1.27 1.27)
				)
				(justify right)
			)
		)
		(property "Value" "C_100n_0201"
			(at 205.74 73.66 0)
			(effects
				(font
					(size 1.27 1.27)
					(thickness 0.15)
				)
				(justify left bottom)
				(hide yes)
			)
		)
		(property "Footprint" "antmicro-footprints:C_0201"
			(at 208.28 73.66 0)
			(effects
				(font
					(size 1.27 1.27)
					(thickness 0.15)
				)
				(justify left bottom)
				(hide yes)
			)
		)
		(property "Datasheet" "https://www.yageo.com/en/Chart/Download/pdf/CC0201KRX6S5BB104"
			(at 210.82 73.66 0)
			(effects
				(font
					(size 1.27 1.27)
					(thickness 0.15)
				)
				(justify left bottom)
				(hide yes)
			)
		)
		(property "Description" ""
			(at 195.58 93.98 0)
			(effects
				(font
					(size 1.27 1.27)
				)
			)
		)
		(property "Manufacturer" "YAGEO"
			(at 215.9 73.66 0)
			(effects
				(font
					(size 1.27 1.27)
					(thickness 0.15)
				)
				(justify left bottom)
				(hide yes)
			)
		)
		(property "MPN" "CC0201KRX6S5BB104"
			(at 213.36 73.66 0)
			(effects
				(font
					(size 1.27 1.27)
					(thickness 0.15)
				)
				(justify left bottom)
				(hide yes)
			)
		)
		(property "Val" "100n"
			(at 196.215 93.345 90)
			(effects
				(font
					(size 1.27 1.27)
					(thickness 0.15)
				)
				(justify right)
			)
		)
		(property "License" "Apache-2.0"
			(at 218.44 73.66 0)
			(effects
				(font
					(size 1.27 1.27)
					(thickness 0.15)
				)
				(justify left bottom)
				(hide yes)
			)
		)
		(property "Author" "Antmicro"
			(at 220.98 73.66 0)
			(effects
				(font
					(size 1.27 1.27)
					(thickness 0.15)
				)
				(justify left bottom)
				(hide yes)
			)
		)
		(property "Voltage" ""
			(at 223.52 73.66 0)
			(effects
				(font
					(size 1.27 1.27)
				)
				(justify left bottom)
				(hide yes)
			)
		)
		(property "Dielectric" ""
			(at 226.06 73.66 0)
			(effects
				(font
					(size 1.27 1.27)
				)
				(justify left bottom)
				(hide yes)
			)
		)
		(pin "1"
		)
		(pin "2"
		)
		(instances
			(project "k410t-devboard"
				(path ""
					(reference "C149")
					(unit 1)
				)
			)
		)
	)
	(symbol
		(lib_id "antmicropower:GND")
		(at 214.63 172.72 0)
		(unit 1)
		(exclude_from_sim no)
		(in_bom yes)
		(on_board yes)
		(dnp no)
		(property "Reference" "#PWR0490"
			(at 214.63 179.07 0)
			(effects
				(font
					(size 1.27 1.27)
				)
				(hide yes)
			)
		)
		(property "Value" "GND"
			(at 214.63 176.53 0)
			(effects
				(font
					(size 1.27 1.27)
				)
			)
		)
		(property "Footprint" ""
			(at 223.52 180.34 0)
			(effects
				(font
					(size 1.27 1.27)
					(thickness 0.15)
				)
				(justify left bottom)
				(hide yes)
			)
		)
		(property "Datasheet" ""
			(at 223.52 185.42 0)
			(effects
				(font
					(size 1.27 1.27)
					(thickness 0.15)
				)
				(justify left bottom)
				(hide yes)
			)
		)
		(property "Description" ""
			(at 214.63 172.72 0)
			(effects
				(font
					(size 1.27 1.27)
				)
			)
		)
		(property "Author" "Antmicro"
			(at 223.52 180.34 0)
			(effects
				(font
					(size 1.27 1.27)
					(thickness 0.15)
				)
				(justify left bottom)
				(hide yes)
			)
		)
		(property "License" "Apache-2.0"
			(at 223.52 182.88 0)
			(effects
				(font
					(size 1.27 1.27)
					(thickness 0.15)
				)
				(justify left bottom)
				(hide yes)
			)
		)
		(pin "1"
		)
		(instances
			(project "k410t-devboard"
				(path ""
					(reference "#PWR0490")
					(unit 1)
				)
			)
		)
	)
	(symbol
		(lib_id "antmicroCapacitorsmisc:C_100n_0201")
		(at 180.34 93.98 90)
		(unit 1)
		(exclude_from_sim no)
		(in_bom yes)
		(on_board yes)
		(dnp no)
		(property "Reference" "C145"
			(at 180.975 89.535 90)
			(effects
				(font
					(size 1.27 1.27)
				)
				(justify right)
			)
		)
		(property "Value" "C_100n_0201"
			(at 190.5 73.66 0)
			(effects
				(font
					(size 1.27 1.27)
					(thickness 0.15)
				)
				(justify left bottom)
				(hide yes)
			)
		)
		(property "Footprint" "antmicro-footprints:C_0201"
			(at 193.04 73.66 0)
			(effects
				(font
					(size 1.27 1.27)
					(thickness 0.15)
				)
				(justify left bottom)
				(hide yes)
			)
		)
		(property "Datasheet" "https://www.yageo.com/en/Chart/Download/pdf/CC0201KRX6S5BB104"
			(at 195.58 73.66 0)
			(effects
				(font
					(size 1.27 1.27)
					(thickness 0.15)
				)
				(justify left bottom)
				(hide yes)
			)
		)
		(property "Description" ""
			(at 180.34 93.98 0)
			(effects
				(font
					(size 1.27 1.27)
				)
			)
		)
		(property "Manufacturer" "YAGEO"
			(at 200.66 73.66 0)
			(effects
				(font
					(size 1.27 1.27)
					(thickness 0.15)
				)
				(justify left bottom)
				(hide yes)
			)
		)
		(property "MPN" "CC0201KRX6S5BB104"
			(at 198.12 73.66 0)
			(effects
				(font
					(size 1.27 1.27)
					(thickness 0.15)
				)
				(justify left bottom)
				(hide yes)
			)
		)
		(property "Val" "100n"
			(at 180.975 93.345 90)
			(effects
				(font
					(size 1.27 1.27)
					(thickness 0.15)
				)
				(justify right)
			)
		)
		(property "License" "Apache-2.0"
			(at 203.2 73.66 0)
			(effects
				(font
					(size 1.27 1.27)
					(thickness 0.15)
				)
				(justify left bottom)
				(hide yes)
			)
		)
		(property "Author" "Antmicro"
			(at 205.74 73.66 0)
			(effects
				(font
					(size 1.27 1.27)
					(thickness 0.15)
				)
				(justify left bottom)
				(hide yes)
			)
		)
		(property "Voltage" ""
			(at 208.28 73.66 0)
			(effects
				(font
					(size 1.27 1.27)
				)
				(justify left bottom)
				(hide yes)
			)
		)
		(property "Dielectric" ""
			(at 210.82 73.66 0)
			(effects
				(font
					(size 1.27 1.27)
				)
				(justify left bottom)
				(hide yes)
			)
		)
		(pin "1"
		)
		(pin "2"
		)
		(instances
			(project "k410t-devboard"
				(path ""
					(reference "C145")
					(unit 1)
				)
			)
		)
	)
	(symbol
		(lib_id "antmicropower:+3.3V")
		(at 367.03 219.71 0)
		(mirror y)
		(unit 1)
		(exclude_from_sim no)
		(in_bom yes)
		(on_board yes)
		(dnp no)
		(property "Reference" "#PWR0381"
			(at 367.03 223.52 0)
			(effects
				(font
					(size 1.27 1.27)
				)
				(hide yes)
			)
		)
		(property "Value" "+3V3"
			(at 367.03 216.154 0)
			(effects
				(font
					(size 1.27 1.27)
				)
			)
		)
		(property "Footprint" ""
			(at 367.03 219.71 0)
			(effects
				(font
					(size 1.27 1.27)
				)
				(hide yes)
			)
		)
		(property "Datasheet" ""
			(at 367.03 219.71 0)
			(effects
				(font
					(size 1.27 1.27)
				)
				(hide yes)
			)
		)
		(property "Description" ""
			(at 367.03 219.71 0)
			(effects
				(font
					(size 1.27 1.27)
				)
			)
		)
		(pin "1"
		)
		(instances
			(project "k410t-devboard"
				(path ""
					(reference "#PWR0381")
					(unit 1)
				)
			)
		)
	)
	(symbol
		(lib_id "antmicropower:GND")
		(at 100.33 242.57 0)
		(unit 1)
		(exclude_from_sim no)
		(in_bom yes)
		(on_board yes)
		(dnp no)
		(property "Reference" "#PWR0487"
			(at 100.33 248.92 0)
			(effects
				(font
					(size 1.27 1.27)
				)
				(hide yes)
			)
		)
		(property "Value" "GND"
			(at 100.33 246.38 0)
			(effects
				(font
					(size 1.27 1.27)
				)
			)
		)
		(property "Footprint" ""
			(at 109.22 250.19 0)
			(effects
				(font
					(size 1.27 1.27)
					(thickness 0.15)
				)
				(justify left bottom)
				(hide yes)
			)
		)
		(property "Datasheet" ""
			(at 109.22 255.27 0)
			(effects
				(font
					(size 1.27 1.27)
					(thickness 0.15)
				)
				(justify left bottom)
				(hide yes)
			)
		)
		(property "Description" ""
			(at 100.33 242.57 0)
			(effects
				(font
					(size 1.27 1.27)
				)
			)
		)
		(property "Author" "Antmicro"
			(at 109.22 250.19 0)
			(effects
				(font
					(size 1.27 1.27)
					(thickness 0.15)
				)
				(justify left bottom)
				(hide yes)
			)
		)
		(property "License" "Apache-2.0"
			(at 109.22 252.73 0)
			(effects
				(font
					(size 1.27 1.27)
					(thickness 0.15)
				)
				(justify left bottom)
				(hide yes)
			)
		)
		(pin "1"
		)
		(instances
			(project "k410t-devboard"
				(path ""
					(reference "#PWR0487")
					(unit 1)
				)
			)
		)
	)
	(symbol
		(lib_id "antmicroCapacitorsmisc:C_100n_0201")
		(at 187.96 76.2 90)
		(unit 1)
		(exclude_from_sim no)
		(in_bom yes)
		(on_board yes)
		(dnp no)
		(property "Reference" "C148"
			(at 188.595 71.755 90)
			(effects
				(font
					(size 1.27 1.27)
				)
				(justify right)
			)
		)
		(property "Value" "C_100n_0201"
			(at 198.12 55.88 0)
			(effects
				(font
					(size 1.27 1.27)
					(thickness 0.15)
				)
				(justify left bottom)
				(hide yes)
			)
		)
		(property "Footprint" "antmicro-footprints:C_0201"
			(at 200.66 55.88 0)
			(effects
				(font
					(size 1.27 1.27)
					(thickness 0.15)
				)
				(justify left bottom)
				(hide yes)
			)
		)
		(property "Datasheet" "https://www.yageo.com/en/Chart/Download/pdf/CC0201KRX6S5BB104"
			(at 203.2 55.88 0)
			(effects
				(font
					(size 1.27 1.27)
					(thickness 0.15)
				)
				(justify left bottom)
				(hide yes)
			)
		)
		(property "Description" ""
			(at 187.96 76.2 0)
			(effects
				(font
					(size 1.27 1.27)
				)
			)
		)
		(property "Manufacturer" "YAGEO"
			(at 208.28 55.88 0)
			(effects
				(font
					(size 1.27 1.27)
					(thickness 0.15)
				)
				(justify left bottom)
				(hide yes)
			)
		)
		(property "MPN" "CC0201KRX6S5BB104"
			(at 205.74 55.88 0)
			(effects
				(font
					(size 1.27 1.27)
					(thickness 0.15)
				)
				(justify left bottom)
				(hide yes)
			)
		)
		(property "Val" "100n"
			(at 188.595 75.565 90)
			(effects
				(font
					(size 1.27 1.27)
					(thickness 0.15)
				)
				(justify right)
			)
		)
		(property "License" "Apache-2.0"
			(at 210.82 55.88 0)
			(effects
				(font
					(size 1.27 1.27)
					(thickness 0.15)
				)
				(justify left bottom)
				(hide yes)
			)
		)
		(property "Author" "Antmicro"
			(at 213.36 55.88 0)
			(effects
				(font
					(size 1.27 1.27)
					(thickness 0.15)
				)
				(justify left bottom)
				(hide yes)
			)
		)
		(property "Voltage" ""
			(at 215.9 55.88 0)
			(effects
				(font
					(size 1.27 1.27)
				)
				(justify left bottom)
				(hide yes)
			)
		)
		(property "Dielectric" ""
			(at 218.44 55.88 0)
			(effects
				(font
					(size 1.27 1.27)
				)
				(justify left bottom)
				(hide yes)
			)
		)
		(pin "1"
		)
		(pin "2"
		)
		(instances
			(project "k410t-devboard"
				(path ""
					(reference "C148")
					(unit 1)
				)
			)
		)
	)
	(symbol
		(lib_id "antmicroCapacitors0603:C_47u_0603")
		(at 191.77 151.13 90)
		(unit 1)
		(exclude_from_sim no)
		(in_bom yes)
		(on_board yes)
		(dnp no)
		(property "Reference" "C49"
			(at 192.405 146.685 90)
			(effects
				(font
					(size 1.27 1.27)
				)
				(justify right)
			)
		)
		(property "Value" "C_47u_0603"
			(at 201.93 130.81 0)
			(effects
				(font
					(size 1.27 1.27)
					(thickness 0.15)
				)
				(justify left bottom)
				(hide yes)
			)
		)
		(property "Footprint" "antmicro-footprints:C_0603_1608Metric"
			(at 204.47 130.81 0)
			(effects
				(font
					(size 1.27 1.27)
					(thickness 0.15)
				)
				(justify left bottom)
				(hide yes)
			)
		)
		(property "Datasheet" "https://www.murata.com/products/productdetail?partno=GRM188R60J476ME15%23"
			(at 207.01 130.81 0)
			(effects
				(font
					(size 1.27 1.27)
					(thickness 0.15)
				)
				(justify left bottom)
				(hide yes)
			)
		)
		(property "Description" ""
			(at 191.77 151.13 0)
			(effects
				(font
					(size 1.27 1.27)
				)
			)
		)
		(property "Manufacturer" "Murata"
			(at 212.09 130.81 0)
			(effects
				(font
					(size 1.27 1.27)
					(thickness 0.15)
				)
				(justify left bottom)
				(hide yes)
			)
		)
		(property "MPN" "GRM188R60J476ME15D"
			(at 209.55 130.81 0)
			(effects
				(font
					(size 1.27 1.27)
					(thickness 0.15)
				)
				(justify left bottom)
				(hide yes)
			)
		)
		(property "Val" "47u"
			(at 192.405 150.495 90)
			(effects
				(font
					(size 1.27 1.27)
					(thickness 0.15)
				)
				(justify right)
			)
		)
		(property "License" "Apache-2.0"
			(at 214.63 130.81 0)
			(effects
				(font
					(size 1.27 1.27)
					(thickness 0.15)
				)
				(justify left bottom)
				(hide yes)
			)
		)
		(property "Author" "Antmicro"
			(at 217.17 130.81 0)
			(effects
				(font
					(size 1.27 1.27)
					(thickness 0.15)
				)
				(justify left bottom)
				(hide yes)
			)
		)
		(property "Voltage" ""
			(at 219.71 130.81 0)
			(effects
				(font
					(size 1.27 1.27)
				)
				(justify left bottom)
				(hide yes)
			)
		)
		(property "Dielectric" ""
			(at 222.25 130.81 0)
			(effects
				(font
					(size 1.27 1.27)
				)
				(justify left bottom)
				(hide yes)
			)
		)
		(pin "1"
		)
		(pin "2"
		)
		(instances
			(project "k410t-devboard"
				(path ""
					(reference "C49")
					(unit 1)
				)
			)
		)
	)
	(symbol
		(lib_id "antmicroCapacitors0402:C_100n_0402")
		(at 207.01 151.13 90)
		(unit 1)
		(exclude_from_sim no)
		(in_bom yes)
		(on_board yes)
		(dnp no)
		(property "Reference" "C53"
			(at 211.455 146.685 90)
			(effects
				(font
					(size 1.27 1.27)
				)
				(justify left)
			)
		)
		(property "Value" "C_100n_0402"
			(at 217.17 130.81 0)
			(effects
				(font
					(size 1.27 1.27)
					(thickness 0.15)
				)
				(justify left bottom)
				(hide yes)
			)
		)
		(property "Footprint" "antmicro-footprints:C_0402_1005Metric"
			(at 219.71 130.81 0)
			(effects
				(font
					(size 1.27 1.27)
					(thickness 0.15)
				)
				(justify left bottom)
				(hide yes)
			)
		)
		(property "Datasheet" "https://www.murata.com/products/productdetail?partno=GRM155R61H104KE14%23"
			(at 222.25 130.81 0)
			(effects
				(font
					(size 1.27 1.27)
					(thickness 0.15)
				)
				(justify left bottom)
				(hide yes)
			)
		)
		(property "Description" ""
			(at 207.01 151.13 0)
			(effects
				(font
					(size 1.27 1.27)
				)
			)
		)
		(property "Manufacturer" "Murata"
			(at 227.33 130.81 0)
			(effects
				(font
					(size 1.27 1.27)
					(thickness 0.15)
				)
				(justify left bottom)
				(hide yes)
			)
		)
		(property "MPN" "GRM155R61H104KE14D"
			(at 224.79 130.81 0)
			(effects
				(font
					(size 1.27 1.27)
					(thickness 0.15)
				)
				(justify left bottom)
				(hide yes)
			)
		)
		(property "Val" "100n"
			(at 212.725 150.495 90)
			(effects
				(font
					(size 1.27 1.27)
					(thickness 0.15)
				)
				(justify left)
			)
		)
		(property "License" "Apache-2.0"
			(at 229.87 130.81 0)
			(effects
				(font
					(size 1.27 1.27)
					(thickness 0.15)
				)
				(justify left bottom)
				(hide yes)
			)
		)
		(property "Author" "Antmicro"
			(at 232.41 130.81 0)
			(effects
				(font
					(size 1.27 1.27)
					(thickness 0.15)
				)
				(justify left bottom)
				(hide yes)
			)
		)
		(property "Voltage" "50V"
			(at 234.95 130.81 0)
			(effects
				(font
					(size 1.27 1.27)
				)
				(justify left bottom)
				(hide yes)
			)
		)
		(property "Dielectric" "X5R"
			(at 237.49 130.81 0)
			(effects
				(font
					(size 1.27 1.27)
				)
				(justify left bottom)
				(hide yes)
			)
		)
		(pin "1"
		)
		(pin "2"
		)
		(instances
			(project "k410t-devboard"
				(path ""
					(reference "C53")
					(unit 1)
				)
			)
		)
	)
	(symbol
		(lib_id "antmicroCapacitors0402:C_100n_0402")
		(at 229.87 168.91 90)
		(unit 1)
		(exclude_from_sim no)
		(in_bom yes)
		(on_board yes)
		(dnp no)
		(property "Reference" "C64"
			(at 230.505 164.465 90)
			(effects
				(font
					(size 1.27 1.27)
				)
				(justify right)
			)
		)
		(property "Value" "C_100n_0402"
			(at 240.03 148.59 0)
			(effects
				(font
					(size 1.27 1.27)
					(thickness 0.15)
				)
				(justify left bottom)
				(hide yes)
			)
		)
		(property "Footprint" "antmicro-footprints:C_0402_1005Metric"
			(at 242.57 148.59 0)
			(effects
				(font
					(size 1.27 1.27)
					(thickness 0.15)
				)
				(justify left bottom)
				(hide yes)
			)
		)
		(property "Datasheet" "https://www.murata.com/products/productdetail?partno=GRM155R61H104KE14%23"
			(at 245.11 148.59 0)
			(effects
				(font
					(size 1.27 1.27)
					(thickness 0.15)
				)
				(justify left bottom)
				(hide yes)
			)
		)
		(property "Description" ""
			(at 229.87 168.91 0)
			(effects
				(font
					(size 1.27 1.27)
				)
			)
		)
		(property "Manufacturer" "Murata"
			(at 250.19 148.59 0)
			(effects
				(font
					(size 1.27 1.27)
					(thickness 0.15)
				)
				(justify left bottom)
				(hide yes)
			)
		)
		(property "MPN" "GRM155R61H104KE14D"
			(at 247.65 148.59 0)
			(effects
				(font
					(size 1.27 1.27)
					(thickness 0.15)
				)
				(justify left bottom)
				(hide yes)
			)
		)
		(property "Val" "100n"
			(at 230.505 168.275 90)
			(effects
				(font
					(size 1.27 1.27)
					(thickness 0.15)
				)
				(justify right)
			)
		)
		(property "License" "Apache-2.0"
			(at 252.73 148.59 0)
			(effects
				(font
					(size 1.27 1.27)
					(thickness 0.15)
				)
				(justify left bottom)
				(hide yes)
			)
		)
		(property "Author" "Antmicro"
			(at 255.27 148.59 0)
			(effects
				(font
					(size 1.27 1.27)
					(thickness 0.15)
				)
				(justify left bottom)
				(hide yes)
			)
		)
		(property "Voltage" "50V"
			(at 257.81 148.59 0)
			(effects
				(font
					(size 1.27 1.27)
				)
				(justify left bottom)
				(hide yes)
			)
		)
		(property "Dielectric" "X5R"
			(at 260.35 148.59 0)
			(effects
				(font
					(size 1.27 1.27)
				)
				(justify left bottom)
				(hide yes)
			)
		)
		(pin "1"
		)
		(pin "2"
		)
		(instances
			(project "k410t-devboard"
				(path ""
					(reference "C64")
					(unit 1)
				)
			)
		)
	)
	(symbol
		(lib_id "antmicropower:GND")
		(at 184.15 154.94 0)
		(unit 1)
		(exclude_from_sim no)
		(in_bom yes)
		(on_board yes)
		(dnp no)
		(property "Reference" "#PWR0489"
			(at 184.15 161.29 0)
			(effects
				(font
					(size 1.27 1.27)
				)
				(hide yes)
			)
		)
		(property "Value" "GND"
			(at 184.15 158.75 0)
			(effects
				(font
					(size 1.27 1.27)
				)
			)
		)
		(property "Footprint" ""
			(at 193.04 162.56 0)
			(effects
				(font
					(size 1.27 1.27)
					(thickness 0.15)
				)
				(justify left bottom)
				(hide yes)
			)
		)
		(property "Datasheet" ""
			(at 193.04 167.64 0)
			(effects
				(font
					(size 1.27 1.27)
					(thickness 0.15)
				)
				(justify left bottom)
				(hide yes)
			)
		)
		(property "Description" ""
			(at 184.15 154.94 0)
			(effects
				(font
					(size 1.27 1.27)
				)
			)
		)
		(property "Author" "Antmicro"
			(at 193.04 162.56 0)
			(effects
				(font
					(size 1.27 1.27)
					(thickness 0.15)
				)
				(justify left bottom)
				(hide yes)
			)
		)
		(property "License" "Apache-2.0"
			(at 193.04 165.1 0)
			(effects
				(font
					(size 1.27 1.27)
					(thickness 0.15)
				)
				(justify left bottom)
				(hide yes)
			)
		)
		(pin "1"
		)
		(instances
			(project "k410t-devboard"
				(path ""
					(reference "#PWR0489")
					(unit 1)
				)
			)
		)
	)
	(symbol
		(lib_id "antmicropower:GND")
		(at 149.86 40.64 0)
		(unit 1)
		(exclude_from_sim no)
		(in_bom yes)
		(on_board yes)
		(dnp no)
		(property "Reference" "#PWR09"
			(at 149.86 46.99 0)
			(effects
				(font
					(size 1.27 1.27)
				)
				(hide yes)
			)
		)
		(property "Value" "GND"
			(at 149.86 44.45 0)
			(effects
				(font
					(size 1.27 1.27)
				)
			)
		)
		(property "Footprint" ""
			(at 158.75 48.26 0)
			(effects
				(font
					(size 1.27 1.27)
					(thickness 0.15)
				)
				(justify left bottom)
				(hide yes)
			)
		)
		(property "Datasheet" ""
			(at 158.75 53.34 0)
			(effects
				(font
					(size 1.27 1.27)
					(thickness 0.15)
				)
				(justify left bottom)
				(hide yes)
			)
		)
		(property "Description" ""
			(at 149.86 40.64 0)
			(effects
				(font
					(size 1.27 1.27)
				)
			)
		)
		(property "Author" "Antmicro"
			(at 158.75 48.26 0)
			(effects
				(font
					(size 1.27 1.27)
					(thickness 0.15)
				)
				(justify left bottom)
				(hide yes)
			)
		)
		(property "License" "Apache-2.0"
			(at 158.75 50.8 0)
			(effects
				(font
					(size 1.27 1.27)
					(thickness 0.15)
				)
				(justify left bottom)
				(hide yes)
			)
		)
		(pin "1"
		)
		(instances
			(project "k410t-devboard"
				(path ""
					(reference "#PWR09")
					(unit 1)
				)
			)
		)
	)
	(symbol
		(lib_id "antmicroCapacitorsmisc:C_100n_0201")
		(at 214.63 220.98 270)
		(mirror x)
		(unit 1)
		(exclude_from_sim no)
		(in_bom yes)
		(on_board yes)
		(dnp no)
		(property "Reference" "C127"
			(at 213.995 216.535 90)
			(effects
				(font
					(size 1.27 1.27)
				)
				(justify right)
			)
		)
		(property "Value" "C_100n_0201"
			(at 204.47 200.66 0)
			(effects
				(font
					(size 1.27 1.27)
					(thickness 0.15)
				)
				(justify left bottom)
				(hide yes)
			)
		)
		(property "Footprint" "antmicro-footprints:C_0201"
			(at 201.93 200.66 0)
			(effects
				(font
					(size 1.27 1.27)
					(thickness 0.15)
				)
				(justify left bottom)
				(hide yes)
			)
		)
		(property "Datasheet" "https://www.yageo.com/en/Chart/Download/pdf/CC0201KRX6S5BB104"
			(at 199.39 200.66 0)
			(effects
				(font
					(size 1.27 1.27)
					(thickness 0.15)
				)
				(justify left bottom)
				(hide yes)
			)
		)
		(property "Description" ""
			(at 214.63 220.98 0)
			(effects
				(font
					(size 1.27 1.27)
				)
			)
		)
		(property "Manufacturer" "YAGEO"
			(at 194.31 200.66 0)
			(effects
				(font
					(size 1.27 1.27)
					(thickness 0.15)
				)
				(justify left bottom)
				(hide yes)
			)
		)
		(property "MPN" "CC0201KRX6S5BB104"
			(at 196.85 200.66 0)
			(effects
				(font
					(size 1.27 1.27)
					(thickness 0.15)
				)
				(justify left bottom)
				(hide yes)
			)
		)
		(property "Val" "100n"
			(at 213.995 220.345 90)
			(effects
				(font
					(size 1.27 1.27)
					(thickness 0.15)
				)
				(justify right)
			)
		)
		(property "License" "Apache-2.0"
			(at 191.77 200.66 0)
			(effects
				(font
					(size 1.27 1.27)
					(thickness 0.15)
				)
				(justify left bottom)
				(hide yes)
			)
		)
		(property "Author" "Antmicro"
			(at 189.23 200.66 0)
			(effects
				(font
					(size 1.27 1.27)
					(thickness 0.15)
				)
				(justify left bottom)
				(hide yes)
			)
		)
		(property "Voltage" ""
			(at 186.69 200.66 0)
			(effects
				(font
					(size 1.27 1.27)
				)
				(justify left bottom)
				(hide yes)
			)
		)
		(property "Dielectric" ""
			(at 184.15 200.66 0)
			(effects
				(font
					(size 1.27 1.27)
				)
				(justify left bottom)
				(hide yes)
			)
		)
		(pin "1"
		)
		(pin "2"
		)
		(instances
			(project "k410t-devboard"
				(path ""
					(reference "C127")
					(unit 1)
				)
			)
		)
	)
	(symbol
		(lib_id "antmicropower:GND")
		(at 219.71 57.15 0)
		(mirror y)
		(unit 1)
		(exclude_from_sim no)
		(in_bom yes)
		(on_board yes)
		(dnp no)
		(property "Reference" "#PWR021"
			(at 219.71 63.5 0)
			(effects
				(font
					(size 1.27 1.27)
				)
				(hide yes)
			)
		)
		(property "Value" "GND"
			(at 219.71 60.96 0)
			(effects
				(font
					(size 1.27 1.27)
				)
			)
		)
		(property "Footprint" ""
			(at 210.82 64.77 0)
			(effects
				(font
					(size 1.27 1.27)
					(thickness 0.15)
				)
				(justify left bottom)
				(hide yes)
			)
		)
		(property "Datasheet" ""
			(at 210.82 69.85 0)
			(effects
				(font
					(size 1.27 1.27)
					(thickness 0.15)
				)
				(justify left bottom)
				(hide yes)
			)
		)
		(property "Description" ""
			(at 219.71 57.15 0)
			(effects
				(font
					(size 1.27 1.27)
				)
			)
		)
		(property "Author" "Antmicro"
			(at 210.82 64.77 0)
			(effects
				(font
					(size 1.27 1.27)
					(thickness 0.15)
				)
				(justify left bottom)
				(hide yes)
			)
		)
		(property "License" "Apache-2.0"
			(at 210.82 67.31 0)
			(effects
				(font
					(size 1.27 1.27)
					(thickness 0.15)
				)
				(justify left bottom)
				(hide yes)
			)
		)
		(pin "1"
		)
		(instances
			(project "k410t-devboard"
				(path ""
					(reference "#PWR021")
					(unit 1)
				)
			)
		)
	)
	(symbol
		(lib_id "antmicropower:GND")
		(at 149.86 80.01 0)
		(unit 1)
		(exclude_from_sim no)
		(in_bom yes)
		(on_board yes)
		(dnp no)
		(property "Reference" "#PWR0503"
			(at 149.86 86.36 0)
			(effects
				(font
					(size 1.27 1.27)
				)
				(hide yes)
			)
		)
		(property "Value" "GND"
			(at 149.86 83.82 0)
			(effects
				(font
					(size 1.27 1.27)
				)
			)
		)
		(property "Footprint" ""
			(at 158.75 87.63 0)
			(effects
				(font
					(size 1.27 1.27)
					(thickness 0.15)
				)
				(justify left bottom)
				(hide yes)
			)
		)
		(property "Datasheet" ""
			(at 158.75 92.71 0)
			(effects
				(font
					(size 1.27 1.27)
					(thickness 0.15)
				)
				(justify left bottom)
				(hide yes)
			)
		)
		(property "Description" ""
			(at 149.86 80.01 0)
			(effects
				(font
					(size 1.27 1.27)
				)
			)
		)
		(property "Author" "Antmicro"
			(at 158.75 87.63 0)
			(effects
				(font
					(size 1.27 1.27)
					(thickness 0.15)
				)
				(justify left bottom)
				(hide yes)
			)
		)
		(property "License" "Apache-2.0"
			(at 158.75 90.17 0)
			(effects
				(font
					(size 1.27 1.27)
					(thickness 0.15)
				)
				(justify left bottom)
				(hide yes)
			)
		)
		(pin "1"
		)
		(instances
			(project "k410t-devboard"
				(path ""
					(reference "#PWR0503")
					(unit 1)
				)
			)
		)
	)
	(symbol
		(lib_id "antmicroCapacitorsmisc:C_100n_0201")
		(at 237.49 201.93 270)
		(mirror x)
		(unit 1)
		(exclude_from_sim no)
		(in_bom yes)
		(on_board yes)
		(dnp no)
		(property "Reference" "C56"
			(at 236.855 197.485 90)
			(effects
				(font
					(size 1.27 1.27)
				)
				(justify right)
			)
		)
		(property "Value" "C_100n_0201"
			(at 227.33 181.61 0)
			(effects
				(font
					(size 1.27 1.27)
					(thickness 0.15)
				)
				(justify left bottom)
				(hide yes)
			)
		)
		(property "Footprint" "antmicro-footprints:C_0201"
			(at 224.79 181.61 0)
			(effects
				(font
					(size 1.27 1.27)
					(thickness 0.15)
				)
				(justify left bottom)
				(hide yes)
			)
		)
		(property "Datasheet" "https://www.yageo.com/en/Chart/Download/pdf/CC0201KRX6S5BB104"
			(at 222.25 181.61 0)
			(effects
				(font
					(size 1.27 1.27)
					(thickness 0.15)
				)
				(justify left bottom)
				(hide yes)
			)
		)
		(property "Description" ""
			(at 237.49 201.93 0)
			(effects
				(font
					(size 1.27 1.27)
				)
			)
		)
		(property "Manufacturer" "YAGEO"
			(at 217.17 181.61 0)
			(effects
				(font
					(size 1.27 1.27)
					(thickness 0.15)
				)
				(justify left bottom)
				(hide yes)
			)
		)
		(property "MPN" "CC0201KRX6S5BB104"
			(at 219.71 181.61 0)
			(effects
				(font
					(size 1.27 1.27)
					(thickness 0.15)
				)
				(justify left bottom)
				(hide yes)
			)
		)
		(property "Val" "100n"
			(at 236.855 201.295 90)
			(effects
				(font
					(size 1.27 1.27)
					(thickness 0.15)
				)
				(justify right)
			)
		)
		(property "License" "Apache-2.0"
			(at 214.63 181.61 0)
			(effects
				(font
					(size 1.27 1.27)
					(thickness 0.15)
				)
				(justify left bottom)
				(hide yes)
			)
		)
		(property "Author" "Antmicro"
			(at 212.09 181.61 0)
			(effects
				(font
					(size 1.27 1.27)
					(thickness 0.15)
				)
				(justify left bottom)
				(hide yes)
			)
		)
		(property "Voltage" ""
			(at 209.55 181.61 0)
			(effects
				(font
					(size 1.27 1.27)
				)
				(justify left bottom)
				(hide yes)
			)
		)
		(property "Dielectric" ""
			(at 207.01 181.61 0)
			(effects
				(font
					(size 1.27 1.27)
				)
				(justify left bottom)
				(hide yes)
			)
		)
		(pin "1"
		)
		(pin "2"
		)
		(instances
			(project "k410t-devboard"
				(path ""
					(reference "C56")
					(unit 1)
				)
			)
		)
	)
	(symbol
		(lib_id "antmicroCapacitors0402:C_100n_0402")
		(at 229.87 220.98 270)
		(mirror x)
		(unit 1)
		(exclude_from_sim no)
		(in_bom yes)
		(on_board yes)
		(dnp no)
		(property "Reference" "C117"
			(at 229.235 216.535 90)
			(effects
				(font
					(size 1.27 1.27)
				)
				(justify right)
			)
		)
		(property "Value" "C_100n_0402"
			(at 219.71 200.66 0)
			(effects
				(font
					(size 1.27 1.27)
					(thickness 0.15)
				)
				(justify left bottom)
				(hide yes)
			)
		)
		(property "Footprint" "antmicro-footprints:C_0402_1005Metric"
			(at 217.17 200.66 0)
			(effects
				(font
					(size 1.27 1.27)
					(thickness 0.15)
				)
				(justify left bottom)
				(hide yes)
			)
		)
		(property "Datasheet" "https://www.murata.com/products/productdetail?partno=GRM155R61H104KE14%23"
			(at 214.63 200.66 0)
			(effects
				(font
					(size 1.27 1.27)
					(thickness 0.15)
				)
				(justify left bottom)
				(hide yes)
			)
		)
		(property "Description" ""
			(at 229.87 220.98 0)
			(effects
				(font
					(size 1.27 1.27)
				)
			)
		)
		(property "Manufacturer" "Murata"
			(at 209.55 200.66 0)
			(effects
				(font
					(size 1.27 1.27)
					(thickness 0.15)
				)
				(justify left bottom)
				(hide yes)
			)
		)
		(property "MPN" "GRM155R61H104KE14D"
			(at 212.09 200.66 0)
			(effects
				(font
					(size 1.27 1.27)
					(thickness 0.15)
				)
				(justify left bottom)
				(hide yes)
			)
		)
		(property "Val" "100n"
			(at 229.235 220.345 90)
			(effects
				(font
					(size 1.27 1.27)
					(thickness 0.15)
				)
				(justify right)
			)
		)
		(property "License" "Apache-2.0"
			(at 207.01 200.66 0)
			(effects
				(font
					(size 1.27 1.27)
					(thickness 0.15)
				)
				(justify left bottom)
				(hide yes)
			)
		)
		(property "Author" "Antmicro"
			(at 204.47 200.66 0)
			(effects
				(font
					(size 1.27 1.27)
					(thickness 0.15)
				)
				(justify left bottom)
				(hide yes)
			)
		)
		(property "Voltage" "50V"
			(at 201.93 200.66 0)
			(effects
				(font
					(size 1.27 1.27)
				)
				(justify left bottom)
				(hide yes)
			)
		)
		(property "Dielectric" "X5R"
			(at 199.39 200.66 0)
			(effects
				(font
					(size 1.27 1.27)
				)
				(justify left bottom)
				(hide yes)
			)
		)
		(pin "1"
		)
		(pin "2"
		)
		(instances
			(project "k410t-devboard"
				(path ""
					(reference "C117")
					(unit 1)
				)
			)
		)
	)
	(symbol
		(lib_id "antmicroCapacitorsmisc:C_100n_0201")
		(at 229.87 201.93 270)
		(mirror x)
		(unit 1)
		(exclude_from_sim no)
		(in_bom yes)
		(on_board yes)
		(dnp no)
		(property "Reference" "C60"
			(at 229.235 197.485 90)
			(effects
				(font
					(size 1.27 1.27)
				)
				(justify right)
			)
		)
		(property "Value" "C_100n_0201"
			(at 219.71 181.61 0)
			(effects
				(font
					(size 1.27 1.27)
					(thickness 0.15)
				)
				(justify left bottom)
				(hide yes)
			)
		)
		(property "Footprint" "antmicro-footprints:C_0201"
			(at 217.17 181.61 0)
			(effects
				(font
					(size 1.27 1.27)
					(thickness 0.15)
				)
				(justify left bottom)
				(hide yes)
			)
		)
		(property "Datasheet" "https://www.yageo.com/en/Chart/Download/pdf/CC0201KRX6S5BB104"
			(at 214.63 181.61 0)
			(effects
				(font
					(size 1.27 1.27)
					(thickness 0.15)
				)
				(justify left bottom)
				(hide yes)
			)
		)
		(property "Description" ""
			(at 229.87 201.93 0)
			(effects
				(font
					(size 1.27 1.27)
				)
			)
		)
		(property "Manufacturer" "YAGEO"
			(at 209.55 181.61 0)
			(effects
				(font
					(size 1.27 1.27)
					(thickness 0.15)
				)
				(justify left bottom)
				(hide yes)
			)
		)
		(property "MPN" "CC0201KRX6S5BB104"
			(at 212.09 181.61 0)
			(effects
				(font
					(size 1.27 1.27)
					(thickness 0.15)
				)
				(justify left bottom)
				(hide yes)
			)
		)
		(property "Val" "100n"
			(at 229.235 201.295 90)
			(effects
				(font
					(size 1.27 1.27)
					(thickness 0.15)
				)
				(justify right)
			)
		)
		(property "License" "Apache-2.0"
			(at 207.01 181.61 0)
			(effects
				(font
					(size 1.27 1.27)
					(thickness 0.15)
				)
				(justify left bottom)
				(hide yes)
			)
		)
		(property "Author" "Antmicro"
			(at 204.47 181.61 0)
			(effects
				(font
					(size 1.27 1.27)
					(thickness 0.15)
				)
				(justify left bottom)
				(hide yes)
			)
		)
		(property "Voltage" ""
			(at 201.93 181.61 0)
			(effects
				(font
					(size 1.27 1.27)
				)
				(justify left bottom)
				(hide yes)
			)
		)
		(property "Dielectric" ""
			(at 199.39 181.61 0)
			(effects
				(font
					(size 1.27 1.27)
				)
				(justify left bottom)
				(hide yes)
			)
		)
		(pin "1"
		)
		(pin "2"
		)
		(instances
			(project "k410t-devboard"
				(path ""
					(reference "C60")
					(unit 1)
				)
			)
		)
	)
	(symbol
		(lib_id "antmicroCapacitorsmisc:C_100n_0201")
		(at 168.91 220.98 270)
		(mirror x)
		(unit 1)
		(exclude_from_sim no)
		(in_bom yes)
		(on_board yes)
		(dnp no)
		(property "Reference" "C141"
			(at 168.275 216.535 90)
			(effects
				(font
					(size 1.27 1.27)
				)
				(justify right)
			)
		)
		(property "Value" "C_100n_0201"
			(at 158.75 200.66 0)
			(effects
				(font
					(size 1.27 1.27)
					(thickness 0.15)
				)
				(justify left bottom)
				(hide yes)
			)
		)
		(property "Footprint" "antmicro-footprints:C_0201"
			(at 156.21 200.66 0)
			(effects
				(font
					(size 1.27 1.27)
					(thickness 0.15)
				)
				(justify left bottom)
				(hide yes)
			)
		)
		(property "Datasheet" "https://www.yageo.com/en/Chart/Download/pdf/CC0201KRX6S5BB104"
			(at 153.67 200.66 0)
			(effects
				(font
					(size 1.27 1.27)
					(thickness 0.15)
				)
				(justify left bottom)
				(hide yes)
			)
		)
		(property "Description" ""
			(at 168.91 220.98 0)
			(effects
				(font
					(size 1.27 1.27)
				)
			)
		)
		(property "Manufacturer" "YAGEO"
			(at 148.59 200.66 0)
			(effects
				(font
					(size 1.27 1.27)
					(thickness 0.15)
				)
				(justify left bottom)
				(hide yes)
			)
		)
		(property "MPN" "CC0201KRX6S5BB104"
			(at 151.13 200.66 0)
			(effects
				(font
					(size 1.27 1.27)
					(thickness 0.15)
				)
				(justify left bottom)
				(hide yes)
			)
		)
		(property "Val" "100n"
			(at 168.275 220.345 90)
			(effects
				(font
					(size 1.27 1.27)
					(thickness 0.15)
				)
				(justify right)
			)
		)
		(property "License" "Apache-2.0"
			(at 146.05 200.66 0)
			(effects
				(font
					(size 1.27 1.27)
					(thickness 0.15)
				)
				(justify left bottom)
				(hide yes)
			)
		)
		(property "Author" "Antmicro"
			(at 143.51 200.66 0)
			(effects
				(font
					(size 1.27 1.27)
					(thickness 0.15)
				)
				(justify left bottom)
				(hide yes)
			)
		)
		(property "Voltage" ""
			(at 140.97 200.66 0)
			(effects
				(font
					(size 1.27 1.27)
				)
				(justify left bottom)
				(hide yes)
			)
		)
		(property "Dielectric" ""
			(at 138.43 200.66 0)
			(effects
				(font
					(size 1.27 1.27)
				)
				(justify left bottom)
				(hide yes)
			)
		)
		(pin "1"
		)
		(pin "2"
		)
		(instances
			(project "k410t-devboard"
				(path ""
					(reference "C141")
					(unit 1)
				)
			)
		)
	)
	(symbol
		(lib_id "antmicropower:+1V0")
		(at 100.33 229.87 0)
		(mirror y)
		(unit 1)
		(exclude_from_sim no)
		(in_bom yes)
		(on_board yes)
		(dnp no)
		(fields_autoplaced yes)
		(property "Reference" "#PWR034"
			(at 100.33 233.68 0)
			(effects
				(font
					(size 1.27 1.27)
				)
				(hide yes)
			)
		)
		(property "Value" "+1V0"
			(at 100.33 226.314 0)
			(effects
				(font
					(size 1.27 1.27)
				)
			)
		)
		(property "Footprint" ""
			(at 100.33 229.87 0)
			(effects
				(font
					(size 1.27 1.27)
				)
				(hide yes)
			)
		)
		(property "Datasheet" ""
			(at 100.33 229.87 0)
			(effects
				(font
					(size 1.27 1.27)
				)
				(hide yes)
			)
		)
		(property "Description" ""
			(at 100.33 229.87 0)
			(effects
				(font
					(size 1.27 1.27)
				)
			)
		)
		(pin "1"
		)
		(instances
			(project "k410t-devboard"
				(path ""
					(reference "#PWR034")
					(unit 1)
				)
			)
		)
	)
	(symbol
		(lib_id "antmicroCapacitors0402:C_100n_0402")
		(at 168.91 238.76 270)
		(mirror x)
		(unit 1)
		(exclude_from_sim no)
		(in_bom yes)
		(on_board yes)
		(dnp no)
		(property "Reference" "C140"
			(at 168.275 234.315 90)
			(effects
				(font
					(size 1.27 1.27)
				)
				(justify right)
			)
		)
		(property "Value" "C_100n_0402"
			(at 158.75 218.44 0)
			(effects
				(font
					(size 1.27 1.27)
					(thickness 0.15)
				)
				(justify left bottom)
				(hide yes)
			)
		)
		(property "Footprint" "antmicro-footprints:C_0402_1005Metric"
			(at 156.21 218.44 0)
			(effects
				(font
					(size 1.27 1.27)
					(thickness 0.15)
				)
				(justify left bottom)
				(hide yes)
			)
		)
		(property "Datasheet" "https://www.murata.com/products/productdetail?partno=GRM155R61H104KE14%23"
			(at 153.67 218.44 0)
			(effects
				(font
					(size 1.27 1.27)
					(thickness 0.15)
				)
				(justify left bottom)
				(hide yes)
			)
		)
		(property "Description" ""
			(at 168.91 238.76 0)
			(effects
				(font
					(size 1.27 1.27)
				)
			)
		)
		(property "Manufacturer" "Murata"
			(at 148.59 218.44 0)
			(effects
				(font
					(size 1.27 1.27)
					(thickness 0.15)
				)
				(justify left bottom)
				(hide yes)
			)
		)
		(property "MPN" "GRM155R61H104KE14D"
			(at 151.13 218.44 0)
			(effects
				(font
					(size 1.27 1.27)
					(thickness 0.15)
				)
				(justify left bottom)
				(hide yes)
			)
		)
		(property "Val" "100n"
			(at 168.275 238.125 90)
			(effects
				(font
					(size 1.27 1.27)
					(thickness 0.15)
				)
				(justify right)
			)
		)
		(property "License" "Apache-2.0"
			(at 146.05 218.44 0)
			(effects
				(font
					(size 1.27 1.27)
					(thickness 0.15)
				)
				(justify left bottom)
				(hide yes)
			)
		)
		(property "Author" "Antmicro"
			(at 143.51 218.44 0)
			(effects
				(font
					(size 1.27 1.27)
					(thickness 0.15)
				)
				(justify left bottom)
				(hide yes)
			)
		)
		(property "Voltage" "50V"
			(at 140.97 218.44 0)
			(effects
				(font
					(size 1.27 1.27)
				)
				(justify left bottom)
				(hide yes)
			)
		)
		(property "Dielectric" "X5R"
			(at 138.43 218.44 0)
			(effects
				(font
					(size 1.27 1.27)
				)
				(justify left bottom)
				(hide yes)
			)
		)
		(pin "1"
		)
		(pin "2"
		)
		(instances
			(project "k410t-devboard"
				(path ""
					(reference "C140")
					(unit 1)
				)
			)
		)
	)
	(symbol
		(lib_id "antmicroCapacitors0603:C_47u_0603")
		(at 199.39 151.13 90)
		(unit 1)
		(exclude_from_sim no)
		(in_bom yes)
		(on_board yes)
		(dnp no)
		(property "Reference" "C51"
			(at 200.025 146.685 90)
			(effects
				(font
					(size 1.27 1.27)
				)
				(justify right)
			)
		)
		(property "Value" "C_47u_0603"
			(at 209.55 130.81 0)
			(effects
				(font
					(size 1.27 1.27)
					(thickness 0.15)
				)
				(justify left bottom)
				(hide yes)
			)
		)
		(property "Footprint" "antmicro-footprints:C_0603_1608Metric"
			(at 212.09 130.81 0)
			(effects
				(font
					(size 1.27 1.27)
					(thickness 0.15)
				)
				(justify left bottom)
				(hide yes)
			)
		)
		(property "Datasheet" "https://www.murata.com/products/productdetail?partno=GRM188R60J476ME15%23"
			(at 214.63 130.81 0)
			(effects
				(font
					(size 1.27 1.27)
					(thickness 0.15)
				)
				(justify left bottom)
				(hide yes)
			)
		)
		(property "Description" ""
			(at 199.39 151.13 0)
			(effects
				(font
					(size 1.27 1.27)
				)
			)
		)
		(property "Manufacturer" "Murata"
			(at 219.71 130.81 0)
			(effects
				(font
					(size 1.27 1.27)
					(thickness 0.15)
				)
				(justify left bottom)
				(hide yes)
			)
		)
		(property "MPN" "GRM188R60J476ME15D"
			(at 217.17 130.81 0)
			(effects
				(font
					(size 1.27 1.27)
					(thickness 0.15)
				)
				(justify left bottom)
				(hide yes)
			)
		)
		(property "Val" "47u"
			(at 200.025 150.495 90)
			(effects
				(font
					(size 1.27 1.27)
					(thickness 0.15)
				)
				(justify right)
			)
		)
		(property "License" "Apache-2.0"
			(at 222.25 130.81 0)
			(effects
				(font
					(size 1.27 1.27)
					(thickness 0.15)
				)
				(justify left bottom)
				(hide yes)
			)
		)
		(property "Author" "Antmicro"
			(at 224.79 130.81 0)
			(effects
				(font
					(size 1.27 1.27)
					(thickness 0.15)
				)
				(justify left bottom)
				(hide yes)
			)
		)
		(property "Voltage" ""
			(at 227.33 130.81 0)
			(effects
				(font
					(size 1.27 1.27)
				)
				(justify left bottom)
				(hide yes)
			)
		)
		(property "Dielectric" ""
			(at 229.87 130.81 0)
			(effects
				(font
					(size 1.27 1.27)
				)
				(justify left bottom)
				(hide yes)
			)
		)
		(pin "1"
		)
		(pin "2"
		)
		(instances
			(project "k410t-devboard"
				(path ""
					(reference "C51")
					(unit 1)
				)
			)
		)
	)
	(symbol
		(lib_id "antmicroCapacitors0402:C_100n_0402")
		(at 237.49 238.76 270)
		(mirror x)
		(unit 1)
		(exclude_from_sim no)
		(in_bom yes)
		(on_board yes)
		(dnp no)
		(property "Reference" "C113"
			(at 236.855 234.315 90)
			(effects
				(font
					(size 1.27 1.27)
				)
				(justify right)
			)
		)
		(property "Value" "C_100n_0402"
			(at 227.33 218.44 0)
			(effects
				(font
					(size 1.27 1.27)
					(thickness 0.15)
				)
				(justify left bottom)
				(hide yes)
			)
		)
		(property "Footprint" "antmicro-footprints:C_0402_1005Metric"
			(at 224.79 218.44 0)
			(effects
				(font
					(size 1.27 1.27)
					(thickness 0.15)
				)
				(justify left bottom)
				(hide yes)
			)
		)
		(property "Datasheet" "https://www.murata.com/products/productdetail?partno=GRM155R61H104KE14%23"
			(at 222.25 218.44 0)
			(effects
				(font
					(size 1.27 1.27)
					(thickness 0.15)
				)
				(justify left bottom)
				(hide yes)
			)
		)
		(property "Description" ""
			(at 237.49 238.76 0)
			(effects
				(font
					(size 1.27 1.27)
				)
			)
		)
		(property "Manufacturer" "Murata"
			(at 217.17 218.44 0)
			(effects
				(font
					(size 1.27 1.27)
					(thickness 0.15)
				)
				(justify left bottom)
				(hide yes)
			)
		)
		(property "MPN" "GRM155R61H104KE14D"
			(at 219.71 218.44 0)
			(effects
				(font
					(size 1.27 1.27)
					(thickness 0.15)
				)
				(justify left bottom)
				(hide yes)
			)
		)
		(property "Val" "100n"
			(at 236.855 238.125 90)
			(effects
				(font
					(size 1.27 1.27)
					(thickness 0.15)
				)
				(justify right)
			)
		)
		(property "License" "Apache-2.0"
			(at 214.63 218.44 0)
			(effects
				(font
					(size 1.27 1.27)
					(thickness 0.15)
				)
				(justify left bottom)
				(hide yes)
			)
		)
		(property "Author" "Antmicro"
			(at 212.09 218.44 0)
			(effects
				(font
					(size 1.27 1.27)
					(thickness 0.15)
				)
				(justify left bottom)
				(hide yes)
			)
		)
		(property "Voltage" "50V"
			(at 209.55 218.44 0)
			(effects
				(font
					(size 1.27 1.27)
				)
				(justify left bottom)
				(hide yes)
			)
		)
		(property "Dielectric" "X5R"
			(at 207.01 218.44 0)
			(effects
				(font
					(size 1.27 1.27)
				)
				(justify left bottom)
				(hide yes)
			)
		)
		(pin "1"
		)
		(pin "2"
		)
		(instances
			(project "k410t-devboard"
				(path ""
					(reference "C113")
					(unit 1)
				)
			)
		)
	)
	(symbol
		(lib_id "antmicroCapacitorsmisc:C_100n_0201")
		(at 203.2 31.75 90)
		(mirror x)
		(unit 1)
		(exclude_from_sim no)
		(in_bom yes)
		(on_board yes)
		(dnp no)
		(property "Reference" "C104"
			(at 203.835 32.385 90)
			(effects
				(font
					(size 1.27 1.27)
				)
				(justify right)
			)
		)
		(property "Value" "C_100n_0201"
			(at 213.36 52.07 0)
			(effects
				(font
					(size 1.27 1.27)
					(thickness 0.15)
				)
				(justify left bottom)
				(hide yes)
			)
		)
		(property "Footprint" "antmicro-footprints:C_0201"
			(at 215.9 52.07 0)
			(effects
				(font
					(size 1.27 1.27)
					(thickness 0.15)
				)
				(justify left bottom)
				(hide yes)
			)
		)
		(property "Datasheet" "https://www.yageo.com/en/Chart/Download/pdf/CC0201KRX6S5BB104"
			(at 218.44 52.07 0)
			(effects
				(font
					(size 1.27 1.27)
					(thickness 0.15)
				)
				(justify left bottom)
				(hide yes)
			)
		)
		(property "Description" ""
			(at 203.2 31.75 0)
			(effects
				(font
					(size 1.27 1.27)
				)
			)
		)
		(property "Manufacturer" "YAGEO"
			(at 223.52 52.07 0)
			(effects
				(font
					(size 1.27 1.27)
					(thickness 0.15)
				)
				(justify left bottom)
				(hide yes)
			)
		)
		(property "MPN" "CC0201KRX6S5BB104"
			(at 220.98 52.07 0)
			(effects
				(font
					(size 1.27 1.27)
					(thickness 0.15)
				)
				(justify left bottom)
				(hide yes)
			)
		)
		(property "Val" "100n"
			(at 203.835 36.195 90)
			(effects
				(font
					(size 1.27 1.27)
					(thickness 0.15)
				)
				(justify right)
			)
		)
		(property "License" "Apache-2.0"
			(at 226.06 52.07 0)
			(effects
				(font
					(size 1.27 1.27)
					(thickness 0.15)
				)
				(justify left bottom)
				(hide yes)
			)
		)
		(property "Author" "Antmicro"
			(at 228.6 52.07 0)
			(effects
				(font
					(size 1.27 1.27)
					(thickness 0.15)
				)
				(justify left bottom)
				(hide yes)
			)
		)
		(property "Voltage" ""
			(at 231.14 52.07 0)
			(effects
				(font
					(size 1.27 1.27)
				)
				(justify left bottom)
				(hide yes)
			)
		)
		(property "Dielectric" ""
			(at 233.68 52.07 0)
			(effects
				(font
					(size 1.27 1.27)
				)
				(justify left bottom)
				(hide yes)
			)
		)
		(pin "1"
		)
		(pin "2"
		)
		(instances
			(project "k410t-devboard"
				(path ""
					(reference "C104")
					(unit 1)
				)
			)
		)
	)
	(symbol
		(lib_id "antmicroCapacitors0402:C_100n_0402")
		(at 214.63 151.13 90)
		(unit 1)
		(exclude_from_sim no)
		(in_bom yes)
		(on_board yes)
		(dnp no)
		(property "Reference" "C55"
			(at 215.265 146.685 90)
			(effects
				(font
					(size 1.27 1.27)
				)
				(justify right)
			)
		)
		(property "Value" "C_100n_0402"
			(at 224.79 130.81 0)
			(effects
				(font
					(size 1.27 1.27)
					(thickness 0.15)
				)
				(justify left bottom)
				(hide yes)
			)
		)
		(property "Footprint" "antmicro-footprints:C_0402_1005Metric"
			(at 227.33 130.81 0)
			(effects
				(font
					(size 1.27 1.27)
					(thickness 0.15)
				)
				(justify left bottom)
				(hide yes)
			)
		)
		(property "Datasheet" "https://www.murata.com/products/productdetail?partno=GRM155R61H104KE14%23"
			(at 229.87 130.81 0)
			(effects
				(font
					(size 1.27 1.27)
					(thickness 0.15)
				)
				(justify left bottom)
				(hide yes)
			)
		)
		(property "Description" ""
			(at 214.63 151.13 0)
			(effects
				(font
					(size 1.27 1.27)
				)
			)
		)
		(property "Manufacturer" "Murata"
			(at 234.95 130.81 0)
			(effects
				(font
					(size 1.27 1.27)
					(thickness 0.15)
				)
				(justify left bottom)
				(hide yes)
			)
		)
		(property "MPN" "GRM155R61H104KE14D"
			(at 232.41 130.81 0)
			(effects
				(font
					(size 1.27 1.27)
					(thickness 0.15)
				)
				(justify left bottom)
				(hide yes)
			)
		)
		(property "Val" "100n"
			(at 215.265 150.495 90)
			(effects
				(font
					(size 1.27 1.27)
					(thickness 0.15)
				)
				(justify right)
			)
		)
		(property "License" "Apache-2.0"
			(at 237.49 130.81 0)
			(effects
				(font
					(size 1.27 1.27)
					(thickness 0.15)
				)
				(justify left bottom)
				(hide yes)
			)
		)
		(property "Author" "Antmicro"
			(at 240.03 130.81 0)
			(effects
				(font
					(size 1.27 1.27)
					(thickness 0.15)
				)
				(justify left bottom)
				(hide yes)
			)
		)
		(property "Voltage" "50V"
			(at 242.57 130.81 0)
			(effects
				(font
					(size 1.27 1.27)
				)
				(justify left bottom)
				(hide yes)
			)
		)
		(property "Dielectric" "X5R"
			(at 245.11 130.81 0)
			(effects
				(font
					(size 1.27 1.27)
				)
				(justify left bottom)
				(hide yes)
			)
		)
		(pin "1"
		)
		(pin "2"
		)
		(instances
			(project "k410t-devboard"
				(path ""
					(reference "C55")
					(unit 1)
				)
			)
		)
	)
	(symbol
		(lib_id "antmicroCapacitorsmisc:C_4u7_0201")
		(at 168.91 201.93 270)
		(mirror x)
		(unit 1)
		(exclude_from_sim no)
		(in_bom yes)
		(on_board yes)
		(dnp no)
		(property "Reference" "C45"
			(at 168.275 197.485 90)
			(effects
				(font
					(size 1.27 1.27)
				)
				(justify right)
			)
		)
		(property "Value" "C_4u7_0201"
			(at 158.75 181.61 0)
			(effects
				(font
					(size 1.27 1.27)
					(thickness 0.15)
				)
				(justify left bottom)
				(hide yes)
			)
		)
		(property "Footprint" "antmicro-footprints:C_0201"
			(at 156.21 181.61 0)
			(effects
				(font
					(size 1.27 1.27)
					(thickness 0.15)
				)
				(justify left bottom)
				(hide yes)
			)
		)
		(property "Datasheet" "https://www.murata.com/products/productdetail?partno=GRM035R60J475ME15%23"
			(at 153.67 181.61 0)
			(effects
				(font
					(size 1.27 1.27)
					(thickness 0.15)
				)
				(justify left bottom)
				(hide yes)
			)
		)
		(property "Description" ""
			(at 168.91 201.93 0)
			(effects
				(font
					(size 1.27 1.27)
				)
			)
		)
		(property "Manufacturer" "Murata"
			(at 148.59 181.61 0)
			(effects
				(font
					(size 1.27 1.27)
					(thickness 0.15)
				)
				(justify left bottom)
				(hide yes)
			)
		)
		(property "MPN" "GRM035R60J475ME15D"
			(at 151.13 181.61 0)
			(effects
				(font
					(size 1.27 1.27)
					(thickness 0.15)
				)
				(justify left bottom)
				(hide yes)
			)
		)
		(property "Val" "4u7"
			(at 168.275 201.295 90)
			(effects
				(font
					(size 1.27 1.27)
					(thickness 0.15)
				)
				(justify right)
			)
		)
		(property "License" "Apache-2.0"
			(at 146.05 181.61 0)
			(effects
				(font
					(size 1.27 1.27)
					(thickness 0.15)
				)
				(justify left bottom)
				(hide yes)
			)
		)
		(property "Author" "Antmicro"
			(at 143.51 181.61 0)
			(effects
				(font
					(size 1.27 1.27)
					(thickness 0.15)
				)
				(justify left bottom)
				(hide yes)
			)
		)
		(property "Voltage" ""
			(at 140.97 181.61 0)
			(effects
				(font
					(size 1.27 1.27)
				)
				(justify left bottom)
				(hide yes)
			)
		)
		(property "Dielectric" ""
			(at 138.43 181.61 0)
			(effects
				(font
					(size 1.27 1.27)
				)
				(justify left bottom)
				(hide yes)
			)
		)
		(pin "1"
		)
		(pin "2"
		)
		(instances
			(project "k410t-devboard"
				(path ""
					(reference "C45")
					(unit 1)
				)
			)
		)
	)
	(symbol
		(lib_id "antmicroCapacitorsmisc:C_100n_0201")
		(at 210.82 76.2 90)
		(unit 1)
		(exclude_from_sim no)
		(in_bom yes)
		(on_board yes)
		(dnp no)
		(property "Reference" "C154"
			(at 211.455 71.755 90)
			(effects
				(font
					(size 1.27 1.27)
				)
				(justify right)
			)
		)
		(property "Value" "C_100n_0201"
			(at 220.98 55.88 0)
			(effects
				(font
					(size 1.27 1.27)
					(thickness 0.15)
				)
				(justify left bottom)
				(hide yes)
			)
		)
		(property "Footprint" "antmicro-footprints:C_0201"
			(at 223.52 55.88 0)
			(effects
				(font
					(size 1.27 1.27)
					(thickness 0.15)
				)
				(justify left bottom)
				(hide yes)
			)
		)
		(property "Datasheet" "https://www.yageo.com/en/Chart/Download/pdf/CC0201KRX6S5BB104"
			(at 226.06 55.88 0)
			(effects
				(font
					(size 1.27 1.27)
					(thickness 0.15)
				)
				(justify left bottom)
				(hide yes)
			)
		)
		(property "Description" ""
			(at 210.82 76.2 0)
			(effects
				(font
					(size 1.27 1.27)
				)
			)
		)
		(property "Manufacturer" "YAGEO"
			(at 231.14 55.88 0)
			(effects
				(font
					(size 1.27 1.27)
					(thickness 0.15)
				)
				(justify left bottom)
				(hide yes)
			)
		)
		(property "MPN" "CC0201KRX6S5BB104"
			(at 228.6 55.88 0)
			(effects
				(font
					(size 1.27 1.27)
					(thickness 0.15)
				)
				(justify left bottom)
				(hide yes)
			)
		)
		(property "Val" "100n"
			(at 211.455 75.565 90)
			(effects
				(font
					(size 1.27 1.27)
					(thickness 0.15)
				)
				(justify right)
			)
		)
		(property "License" "Apache-2.0"
			(at 233.68 55.88 0)
			(effects
				(font
					(size 1.27 1.27)
					(thickness 0.15)
				)
				(justify left bottom)
				(hide yes)
			)
		)
		(property "Author" "Antmicro"
			(at 236.22 55.88 0)
			(effects
				(font
					(size 1.27 1.27)
					(thickness 0.15)
				)
				(justify left bottom)
				(hide yes)
			)
		)
		(property "Voltage" ""
			(at 238.76 55.88 0)
			(effects
				(font
					(size 1.27 1.27)
				)
				(justify left bottom)
				(hide yes)
			)
		)
		(property "Dielectric" ""
			(at 241.3 55.88 0)
			(effects
				(font
					(size 1.27 1.27)
				)
				(justify left bottom)
				(hide yes)
			)
		)
		(pin "1"
		)
		(pin "2"
		)
		(instances
			(project "k410t-devboard"
				(path ""
					(reference "C154")
					(unit 1)
				)
			)
		)
	)
	(symbol
		(lib_id "antmicroCapacitors0402:C_100n_0402")
		(at 237.49 168.91 90)
		(unit 1)
		(exclude_from_sim no)
		(in_bom yes)
		(on_board yes)
		(dnp no)
		(property "Reference" "C73"
			(at 238.125 164.465 90)
			(effects
				(font
					(size 1.27 1.27)
				)
				(justify right)
			)
		)
		(property "Value" "C_100n_0402"
			(at 247.65 148.59 0)
			(effects
				(font
					(size 1.27 1.27)
					(thickness 0.15)
				)
				(justify left bottom)
				(hide yes)
			)
		)
		(property "Footprint" "antmicro-footprints:C_0402_1005Metric"
			(at 250.19 148.59 0)
			(effects
				(font
					(size 1.27 1.27)
					(thickness 0.15)
				)
				(justify left bottom)
				(hide yes)
			)
		)
		(property "Datasheet" "https://www.murata.com/products/productdetail?partno=GRM155R61H104KE14%23"
			(at 252.73 148.59 0)
			(effects
				(font
					(size 1.27 1.27)
					(thickness 0.15)
				)
				(justify left bottom)
				(hide yes)
			)
		)
		(property "Description" ""
			(at 237.49 168.91 0)
			(effects
				(font
					(size 1.27 1.27)
				)
			)
		)
		(property "Manufacturer" "Murata"
			(at 257.81 148.59 0)
			(effects
				(font
					(size 1.27 1.27)
					(thickness 0.15)
				)
				(justify left bottom)
				(hide yes)
			)
		)
		(property "MPN" "GRM155R61H104KE14D"
			(at 255.27 148.59 0)
			(effects
				(font
					(size 1.27 1.27)
					(thickness 0.15)
				)
				(justify left bottom)
				(hide yes)
			)
		)
		(property "Val" "100n"
			(at 238.125 168.275 90)
			(effects
				(font
					(size 1.27 1.27)
					(thickness 0.15)
				)
				(justify right)
			)
		)
		(property "License" "Apache-2.0"
			(at 260.35 148.59 0)
			(effects
				(font
					(size 1.27 1.27)
					(thickness 0.15)
				)
				(justify left bottom)
				(hide yes)
			)
		)
		(property "Author" "Antmicro"
			(at 262.89 148.59 0)
			(effects
				(font
					(size 1.27 1.27)
					(thickness 0.15)
				)
				(justify left bottom)
				(hide yes)
			)
		)
		(property "Voltage" "50V"
			(at 265.43 148.59 0)
			(effects
				(font
					(size 1.27 1.27)
				)
				(justify left bottom)
				(hide yes)
			)
		)
		(property "Dielectric" "X5R"
			(at 267.97 148.59 0)
			(effects
				(font
					(size 1.27 1.27)
				)
				(justify left bottom)
				(hide yes)
			)
		)
		(pin "1"
		)
		(pin "2"
		)
		(instances
			(project "k410t-devboard"
				(path ""
					(reference "C73")
					(unit 1)
				)
			)
		)
	)
)
